G04 ================== begin FILE IDENTIFICATION RECORD ==================*
G04 Layout Name:  9048_F0T_Management_Board_D_brd_V04_1213_1625.brd*
G04 Film Name:    sst*
G04 File Format:  Gerber RS274X*
G04 File Origin:  Cadence Allegro 17.2-S081*
G04 Origin Date:  Tue Dec 13 16:31:11 2022*
G04 *
G04 Layer:  DRAWING FORMAT/TITLE_BLOCK_A*
G04 Layer:  BOARD GEOMETRY/DESIGN_OUTLINE*
G04 Layer:  BOARD GEOMETRY/CUTOUT*
G04 Layer:  BOARD GEOMETRY/OUTLINE*
G04 Layer:  DRAWING FORMAT/TITLE_BLOCK*
G04 Layer:  MANUFACTURING/TP_TEXT_TOP*
G04 Layer:  REF DES/SILKSCREEN_TOP*
G04 Layer:  PACKAGE GEOMETRY/SILKSCREEN_TOP*
G04 Layer:  MANUFACTURING/PHOTOPLOT_OUTLINE*
G04 Layer:  DRAWING FORMAT/TITLE_DATA_SST*
G04 Layer:  BOARD GEOMETRY/SILKSCREEN_TOP*
G04 *
G04 Offset:    (0.00 0.00)*
G04 Mirror:    No*
G04 Mode:      Positive*
G04 Rotation:  0*
G04 FullContactRelief:  No*
G04 UndefLineWidth:     6.00*
G04 ================== end FILE IDENTIFICATION RECORD ====================*
%FSLAX25Y25*MOIN*%
%IR0*IPPOS*OFA0.00000B0.00000*MIA0B0*SFA1.00000B1.00000*%
%ADD10C,.006*%
G75*
%LPD*%
G75*
G36*
G01X16205Y27496D02*
X10587Y24687D01*
Y30305D01*
X16205Y27496D01*
G37*
G36*
G01X13019Y406639D02*
Y411669D01*
X18048Y409154D01*
X13019Y406639D01*
G37*
G36*
G01X23615Y247115D02*
X22248Y249786D01*
X25602Y249817D01*
X23615Y247115D01*
G37*
G36*
G01X24350Y328426D02*
X26085Y327559D01*
X24350Y326692D01*
Y328426D01*
G37*
G36*
G01X39899Y40259D02*
X38160Y41998D01*
X40615Y42626D01*
X39899Y40259D01*
G37*
G36*
G01X43474Y75515D02*
X45428Y77469D01*
X46406Y74537D01*
X43474Y75515D01*
G37*
G36*
G01X41189Y78000D02*
X45189D01*
X43189Y82000D01*
X41189Y78000D01*
G37*
G36*
G01X39394Y188078D02*
Y192078D01*
X35394Y190078D01*
X39394Y188078D01*
G37*
G36*
G01X45760Y218976D02*
X49760D01*
X47760Y222976D01*
X45760Y218976D01*
G37*
G36*
G01X46865Y422208D02*
Y420208D01*
X49865Y421208D01*
X46865Y422208D01*
G37*
G36*
G01X59541Y237800D02*
X61041Y234800D01*
X58041D01*
X59541Y237800D01*
G37*
G36*
G01X67709Y32244D02*
X63709D01*
X65709Y36244D01*
X67709Y32244D01*
G37*
G36*
G01X64659Y151950D02*
X63759Y154250D01*
X65459D01*
X64659Y151950D01*
G37*
G36*
G01X65251Y157827D02*
X67251D01*
X66251Y160827D01*
X65251Y157827D01*
G37*
G36*
G01X65050Y207341D02*
X67350Y208241D01*
Y206541D01*
X65050Y207341D01*
G37*
G36*
G01X69088Y236732D02*
X71916Y233904D01*
X73330Y238147D01*
X69088Y236732D01*
G37*
G36*
G01X70898Y326072D02*
X66898D01*
X68898Y322072D01*
X70898Y326072D01*
G37*
G36*
G01X81105Y133234D02*
X79264Y132620D01*
X79878Y134460D01*
X81105Y133234D01*
G37*
G36*
G01X84941Y237600D02*
X86441Y234600D01*
X83441D01*
X84941Y237600D01*
G37*
G36*
G01X107125Y60625D02*
X108124Y58625D01*
X106125D01*
X107125Y60625D01*
G37*
G36*
G01X104159Y61846D02*
X101330Y59017D01*
X105573Y57603D01*
X104159Y61846D01*
G37*
G36*
G01X93347Y234300D02*
X97347D01*
X95347Y238300D01*
X93347Y234300D01*
G37*
G36*
G01X120458Y47371D02*
X122412Y49325D01*
X123389Y46393D01*
X120458Y47371D01*
G37*
G36*
G01X122389Y58724D02*
X121139Y56224D01*
X123639D01*
X122389Y58724D01*
G37*
G36*
G01X109374Y238150D02*
X110241Y239885D01*
X111108Y238150D01*
X109374D01*
G37*
G36*
G01X119176Y250840D02*
Y246840D01*
X123176Y248840D01*
X119176Y250840D01*
G37*
G36*
G01X123856Y342581D02*
X119056Y337683D01*
X113056Y344083D01*
X108756Y339783D01*
X114356Y333583D01*
X113348Y332657D01*
X123856D01*
Y342581D01*
G37*
G36*
G01X135768Y50677D02*
Y54677D01*
X139768Y52677D01*
X135768Y50677D01*
G37*
G36*
G01X126300Y75823D02*
Y73059D01*
X123536Y74441D01*
X126300Y75823D01*
G37*
G36*
G01X127416Y96400D02*
Y93400D01*
X124416Y94900D01*
X127416Y96400D01*
G37*
G36*
G01X131500Y100063D02*
Y102063D01*
X129500Y101063D01*
X131500Y100063D01*
G37*
G36*
G01Y117563D02*
Y119563D01*
X129500Y118563D01*
X131500Y117563D01*
G37*
G36*
G01X128707Y122488D02*
Y126488D01*
X132707Y124488D01*
X128707Y122488D01*
G37*
G36*
G01X128260Y146600D02*
X131260D01*
X129760Y149600D01*
X128260Y146600D01*
G37*
G36*
G01X136012Y353472D02*
X140012D01*
X138012Y357472D01*
X136012Y353472D01*
G37*
G36*
G01X138012Y357472D02*
X136012Y353472D01*
X140012D01*
X138012Y357472D01*
G37*
G36*
G01X158756Y67637D02*
X160170Y66223D01*
X160877Y68344D01*
X158756Y67637D01*
G37*
G36*
G01X158214Y94796D02*
X156093Y95504D01*
X157507Y96918D01*
X158214Y94796D01*
G37*
G36*
G01X167453Y93743D02*
X165332Y94450D01*
X166746Y95864D01*
X167453Y93743D01*
G37*
G36*
G01X155100Y108200D02*
Y106200D01*
X158100Y107200D01*
X155100Y108200D01*
G37*
G36*
G01X152640Y215841D02*
X153389Y212181D01*
X155435Y213362D01*
X152640Y215841D01*
G37*
G36*
G01X155341Y270350D02*
X156241Y268050D01*
X154541D01*
X155341Y270350D01*
G37*
G36*
G01X211169Y87557D02*
X209111Y88586D01*
X211169Y89615D01*
Y87557D01*
G37*
G36*
G01X221551Y103829D02*
X219550Y99829D01*
X223550Y99828D01*
X221551Y103829D01*
G37*
G36*
G01X214627Y289371D02*
X217455Y292200D01*
X213213Y293614D01*
X214627Y289371D01*
G37*
G36*
G01X214150Y310941D02*
X216450Y311841D01*
Y310141D01*
X214150Y310941D01*
G37*
G36*
G01X217600Y322800D02*
X213600Y324800D01*
X217600Y326800D01*
Y322800D01*
G37*
G36*
G01X240700Y45177D02*
Y47941D01*
X243464Y46559D01*
X240700Y45177D01*
G37*
G36*
G01X257657Y152840D02*
X252342D01*
Y149840D01*
X260657D01*
Y158155D01*
X257657D01*
Y152840D01*
G37*
G36*
G01X259320Y46332D02*
Y48792D01*
X261500Y47500D01*
X259320Y46332D01*
G37*
G36*
G01X269095Y33963D02*
X266286Y39581D01*
X271904D01*
X269095Y33963D01*
G37*
G36*
G01X272066Y132401D02*
X270066D01*
X271066Y130401D01*
X272066Y132401D01*
G37*
G36*
G01X262958Y365606D02*
Y361606D01*
X258958Y363606D01*
X262958Y365606D01*
G37*
G36*
G01X281985Y61306D02*
X284445D01*
X283153Y59126D01*
X281985Y61306D01*
G37*
G36*
G01X276100Y57500D02*
X272100Y59500D01*
X276100Y61500D01*
Y57500D01*
G37*
G36*
G01X273506Y226712D02*
X288406Y226812D01*
X288419Y226822D01*
X283509Y221912D01*
X290114Y215307D01*
X290019Y215212D01*
X285209D01*
Y210512D01*
X285059Y210362D01*
X278509Y216912D01*
X273609Y212012D01*
X273509Y212112D01*
X273506Y226712D01*
G37*
G36*
G01X307544Y27496D02*
X301926Y24687D01*
Y30305D01*
X307544Y27496D01*
G37*
G36*
G01X307240Y337943D02*
X303240D01*
X305240Y333943D01*
X307240Y337943D01*
G37*
G36*
G01X322717Y62412D02*
X324104Y64762D01*
X325151Y62243D01*
X322717Y62412D01*
G37*
G36*
G01X329953Y140432D02*
X333294Y142103D01*
X331624Y143774D01*
X329953Y140432D01*
G37*
G36*
G01X324663Y293435D02*
X323795Y291700D01*
X322928Y293435D01*
X324663D01*
G37*
G36*
G01X327719Y365306D02*
Y361306D01*
X323719Y363306D01*
X327719Y365306D01*
G37*
G36*
G01X451000Y-441001D02*
X454000Y-435001D01*
X448000D01*
X451000Y-441001D01*
G37*
G36*
G01X441000Y-357999D02*
X438000Y-363999D01*
X444000D01*
X441000Y-357999D01*
G37*
G36*
G01X451000Y-320401D02*
X454000Y-314401D01*
X448000D01*
X451000Y-320401D01*
G37*
G36*
G01X441000Y-247999D02*
X438000Y-253999D01*
X444000D01*
X441000Y-247999D01*
G37*
G36*
G01X451000Y14999D02*
X454000Y20999D01*
X448000D01*
X451000Y14999D01*
G37*
G36*
G01X441000Y93001D02*
X438000Y87001D01*
X444000D01*
X441000Y93001D01*
G37*
G36*
G01X451000Y128999D02*
X454000Y134999D01*
X448000D01*
X451000Y128999D01*
G37*
G36*
G01X441000Y197001D02*
X438000Y191001D01*
X444000D01*
X441000Y197001D01*
G37*
G54D10*
G01X2010999Y-388000D02*
Y1475775D01*
X-407000D01*
Y-386798D01*
Y-755294D01*
Y-793716D01*
X-368578D01*
X1942346D01*
X2010999D01*
Y-725063D01*
Y-388000D01*
G01X-53307Y-609436D02*
Y-684436D01*
X446693D01*
Y-609436D01*
X-53307D01*
G01X-41307Y-674436D02*
Y-679436D01*
G01X-42764Y-674436D02*
X-39850D01*
G01X-34940Y-679436D02*
X-37474D01*
Y-674436D01*
X-34940D01*
G01X-35954Y-676853D02*
X-37474D01*
G01X-32374Y-674436D02*
Y-679436D01*
X-29840D01*
G01X-26007Y-679603D02*
X-26134Y-679519D01*
Y-679353D01*
X-26007Y-679269D01*
X-25880Y-679353D01*
Y-679519D01*
X-26007Y-679603D01*
G01Y-677353D02*
X-26134Y-677269D01*
Y-677103D01*
X-26007Y-677019D01*
X-25880Y-677103D01*
Y-677269D01*
X-26007Y-677353D01*
G01X-21224Y-681103D02*
X-21857Y-680269D01*
X-22174Y-679436D01*
Y-676103D01*
X-21857Y-675269D01*
X-21224Y-674436D01*
G01X-15807D02*
X-16314Y-674603D01*
X-16694Y-675019D01*
X-16947Y-675519D01*
X-17137Y-676186D01*
X-17200Y-676936D01*
X-17137Y-677686D01*
X-16947Y-678353D01*
X-16694Y-678853D01*
X-16314Y-679269D01*
X-15807Y-679436D01*
X-15300Y-679269D01*
X-14920Y-678853D01*
X-14667Y-678353D01*
X-14477Y-677686D01*
X-14414Y-676936D01*
X-14477Y-676186D01*
X-14667Y-675519D01*
X-14920Y-675019D01*
X-15300Y-674603D01*
X-15807Y-674436D01*
G01X-12100Y-678436D02*
X-11720Y-679019D01*
X-11214Y-679353D01*
X-10644Y-679436D01*
X-10137Y-679353D01*
X-9630Y-678936D01*
X-9314Y-678436D01*
X-9250Y-677936D01*
X-9377Y-677353D01*
X-9820Y-676936D01*
X-10264Y-676769D01*
X-10834D01*
G01X-10264D02*
X-9884Y-676519D01*
X-9567Y-676103D01*
X-9440Y-675603D01*
X-9567Y-675103D01*
X-9884Y-674686D01*
X-10454Y-674436D01*
X-11024Y-674519D01*
X-11594Y-674853D01*
G01X-5290Y-681103D02*
X-4657Y-680269D01*
X-4340Y-679436D01*
Y-676103D01*
X-4657Y-675269D01*
X-5290Y-674436D01*
G01X-1900Y-678436D02*
X-1520Y-679019D01*
X-1014Y-679353D01*
X-444Y-679436D01*
X63Y-679353D01*
X570Y-678936D01*
X886Y-678436D01*
X950Y-677936D01*
X823Y-677353D01*
X380Y-676936D01*
X-64Y-676769D01*
X-634D01*
G01X-64D02*
X316Y-676519D01*
X633Y-676103D01*
X760Y-675603D01*
X633Y-675103D01*
X316Y-674686D01*
X-254Y-674436D01*
X-824Y-674519D01*
X-1394Y-674853D01*
G01X3390Y-675269D02*
X3770Y-674769D01*
X4213Y-674519D01*
X4720Y-674436D01*
X5353Y-674603D01*
X5796Y-675019D01*
X5923Y-675519D01*
X5860Y-676019D01*
X5606Y-676436D01*
X4340Y-677269D01*
X3770Y-677853D01*
X3390Y-678686D01*
X3263Y-679436D01*
X5923D01*
G01X9566D02*
X9693Y-678353D01*
X9883Y-677436D01*
X10136Y-676603D01*
X10453Y-675686D01*
X10960Y-674436D01*
X8426D01*
G01X13970Y-677769D02*
X15616D01*
G01X18690Y-675269D02*
X19070Y-674769D01*
X19513Y-674519D01*
X20020Y-674436D01*
X20653Y-674603D01*
X21096Y-675019D01*
X21223Y-675519D01*
X21160Y-676019D01*
X20906Y-676436D01*
X19640Y-677269D01*
X19070Y-677853D01*
X18690Y-678686D01*
X18563Y-679436D01*
X21223D01*
G01X23600Y-678436D02*
X23980Y-679019D01*
X24486Y-679353D01*
X25056Y-679436D01*
X25563Y-679353D01*
X26070Y-678936D01*
X26386Y-678436D01*
X26450Y-677936D01*
X26323Y-677353D01*
X25880Y-676936D01*
X25436Y-676769D01*
X24866D01*
G01X25436D02*
X25816Y-676519D01*
X26133Y-676103D01*
X26260Y-675603D01*
X26133Y-675103D01*
X25816Y-674686D01*
X25246Y-674436D01*
X24676Y-674519D01*
X24106Y-674853D01*
G01X30853Y-679436D02*
Y-674436D01*
X28510Y-678019D01*
X31676D01*
G01X33800Y-678686D02*
X34180Y-679103D01*
X34623Y-679353D01*
X35193Y-679436D01*
X35763Y-679269D01*
X36206Y-678936D01*
X36523Y-678353D01*
X36586Y-677686D01*
X36460Y-677019D01*
X36143Y-676603D01*
X35700Y-676269D01*
X35256Y-676186D01*
X34813Y-676269D01*
X34243Y-676603D01*
X34433Y-674436D01*
X36143D01*
G01X44190Y-679436D02*
Y-674436D01*
X46596D01*
G01X45710Y-676853D02*
X44190D01*
G01X48910Y-679436D02*
X50493Y-674436D01*
X52076Y-679436D01*
G01X51506Y-677686D02*
X49480D01*
G01X54263Y-679436D02*
X56923Y-674436D01*
G01X54263D02*
X56923Y-679436D01*
G01X60693Y-679603D02*
X60566Y-679519D01*
Y-679353D01*
X60693Y-679269D01*
X60820Y-679353D01*
Y-679519D01*
X60693Y-679603D01*
G01Y-677353D02*
X60566Y-677269D01*
Y-677103D01*
X60693Y-677019D01*
X60820Y-677103D01*
Y-677269D01*
X60693Y-677353D01*
G01X65476Y-681103D02*
X64843Y-680269D01*
X64526Y-679436D01*
Y-676103D01*
X64843Y-675269D01*
X65476Y-674436D01*
G01X70893D02*
X70386Y-674603D01*
X70006Y-675019D01*
X69753Y-675519D01*
X69563Y-676186D01*
X69500Y-676936D01*
X69563Y-677686D01*
X69753Y-678353D01*
X70006Y-678853D01*
X70386Y-679269D01*
X70893Y-679436D01*
X71400Y-679269D01*
X71780Y-678853D01*
X72033Y-678353D01*
X72223Y-677686D01*
X72286Y-676936D01*
X72223Y-676186D01*
X72033Y-675519D01*
X71780Y-675019D01*
X71400Y-674603D01*
X70893Y-674436D01*
G01X74600Y-678436D02*
X74980Y-679019D01*
X75486Y-679353D01*
X76056Y-679436D01*
X76563Y-679353D01*
X77070Y-678936D01*
X77386Y-678436D01*
X77450Y-677936D01*
X77323Y-677353D01*
X76880Y-676936D01*
X76436Y-676769D01*
X75866D01*
G01X76436D02*
X76816Y-676519D01*
X77133Y-676103D01*
X77260Y-675603D01*
X77133Y-675103D01*
X76816Y-674686D01*
X76246Y-674436D01*
X75676Y-674519D01*
X75106Y-674853D01*
G01X81410Y-681103D02*
X82043Y-680269D01*
X82360Y-679436D01*
Y-676103D01*
X82043Y-675269D01*
X81410Y-674436D01*
G01X84800Y-678436D02*
X85180Y-679019D01*
X85686Y-679353D01*
X86256Y-679436D01*
X86763Y-679353D01*
X87270Y-678936D01*
X87586Y-678436D01*
X87650Y-677936D01*
X87523Y-677353D01*
X87080Y-676936D01*
X86636Y-676769D01*
X86066D01*
G01X86636D02*
X87016Y-676519D01*
X87333Y-676103D01*
X87460Y-675603D01*
X87333Y-675103D01*
X87016Y-674686D01*
X86446Y-674436D01*
X85876Y-674519D01*
X85306Y-674853D01*
G01X90216Y-678853D02*
X90660Y-679269D01*
X91166Y-679436D01*
X91673Y-679269D01*
X92116Y-678769D01*
X92433Y-678019D01*
X92560Y-677269D01*
Y-676353D01*
X92433Y-675603D01*
X92116Y-674936D01*
X91736Y-674603D01*
X91293Y-674436D01*
X90786Y-674603D01*
X90406Y-674936D01*
X90153Y-675436D01*
X90026Y-676103D01*
X90153Y-676686D01*
X90470Y-677269D01*
X90850Y-677603D01*
X91293Y-677686D01*
X91800Y-677519D01*
X92180Y-677103D01*
X92560Y-676353D01*
G01X96266Y-679436D02*
X96393Y-678353D01*
X96583Y-677436D01*
X96836Y-676603D01*
X97153Y-675686D01*
X97660Y-674436D01*
X95126D01*
G01X100670Y-677769D02*
X102316D01*
G01X105200Y-678436D02*
X105580Y-679019D01*
X106086Y-679353D01*
X106656Y-679436D01*
X107163Y-679353D01*
X107670Y-678936D01*
X107986Y-678436D01*
X108050Y-677936D01*
X107923Y-677353D01*
X107480Y-676936D01*
X107036Y-676769D01*
X106466D01*
G01X107036D02*
X107416Y-676519D01*
X107733Y-676103D01*
X107860Y-675603D01*
X107733Y-675103D01*
X107416Y-674686D01*
X106846Y-674436D01*
X106276Y-674519D01*
X105706Y-674853D01*
G01X110490Y-677353D02*
X110933Y-676769D01*
X111313Y-676436D01*
X111820Y-676269D01*
X112263Y-676436D01*
X112580Y-676769D01*
X112833Y-677269D01*
X112896Y-677853D01*
X112833Y-678353D01*
X112580Y-678853D01*
X112200Y-679269D01*
X111756Y-679436D01*
X111250Y-679269D01*
X110806Y-678769D01*
X110553Y-678019D01*
X110490Y-677186D01*
X110616Y-676103D01*
X110806Y-675519D01*
X111123Y-674936D01*
X111566Y-674519D01*
X112010Y-674436D01*
X112453Y-674603D01*
X112770Y-675019D01*
G01X116793Y-679436D02*
Y-674436D01*
X116033Y-675436D01*
G01Y-679436D02*
X117553D01*
G01X122653D02*
Y-674436D01*
X120310Y-678019D01*
X123476D01*
G01X-18220Y538155D02*
Y539155D01*
X-18054D01*
X-17987Y539105D01*
X-17937Y539038D01*
X-17895Y538938D01*
X-17862Y538822D01*
X-17854Y538655D01*
X-17862Y538488D01*
X-17895Y538372D01*
X-17937Y538272D01*
X-17987Y538205D01*
X-18054Y538155D01*
X-18220D01*
G01X-17654D02*
Y539155D01*
X-17437Y538322D01*
X-17220Y539155D01*
Y538155D01*
G01X-16837D02*
Y539155D01*
X-16937Y538955D01*
G01Y538155D02*
X-16737D01*
G01X-17983Y546367D02*
Y547367D01*
X-17817D01*
X-17750Y547317D01*
X-17700Y547250D01*
X-17658Y547150D01*
X-17625Y547034D01*
X-17617Y546867D01*
X-17625Y546700D01*
X-17658Y546584D01*
X-17700Y546484D01*
X-17750Y546417D01*
X-17817Y546367D01*
X-17983D01*
G01X-17417D02*
Y547367D01*
X-17200Y546534D01*
X-16983Y547367D01*
Y546367D01*
G01X-16783Y546567D02*
X-16733Y546450D01*
X-16667Y546384D01*
X-16592Y546367D01*
X-16525Y546384D01*
X-16458Y546467D01*
X-16417Y546567D01*
X-16408Y546667D01*
X-16425Y546784D01*
X-16483Y546867D01*
X-16542Y546900D01*
X-16617D01*
G01X-16542D02*
X-16492Y546950D01*
X-16450Y547034D01*
X-16433Y547134D01*
X-16450Y547234D01*
X-16492Y547317D01*
X-16567Y547367D01*
X-16642Y547350D01*
X-16717Y547284D01*
G01X-25220Y545155D02*
Y546155D01*
X-25054D01*
X-24987Y546105D01*
X-24937Y546038D01*
X-24895Y545938D01*
X-24862Y545822D01*
X-24854Y545655D01*
X-24862Y545488D01*
X-24895Y545372D01*
X-24937Y545272D01*
X-24987Y545205D01*
X-25054Y545155D01*
X-25220D01*
G01X-24654D02*
Y546155D01*
X-24437Y545322D01*
X-24220Y546155D01*
Y545155D01*
G01X-23995Y545988D02*
X-23945Y546088D01*
X-23887Y546138D01*
X-23820Y546155D01*
X-23737Y546122D01*
X-23679Y546038D01*
X-23662Y545938D01*
X-23670Y545838D01*
X-23704Y545755D01*
X-23870Y545588D01*
X-23945Y545472D01*
X-23995Y545305D01*
X-24012Y545155D01*
X-23662D01*
G01X7874Y450000D02*
G03X0Y442126I0J-7874D01*
G01Y335630D01*
G03X984Y334646I984J0D01*
G01X8858D01*
G02X10827Y332677I0J-1969D01*
G01Y322835D01*
G02X8858Y320866I-1969J0D01*
G01X984D01*
G03X0Y319882I0J-984D01*
G01Y7874D01*
G03X7874Y0I7874J0D01*
G01X346457D01*
G03X354331Y7874I0J7874D01*
G01Y319882D01*
G03X353346Y320866I-984J0D01*
G01X345472D01*
G02X343504Y322835I0J1968D01*
G01Y332677D01*
G02X345472Y334646I1968J0D01*
G01X353346D01*
G03X354331Y335630I1J984D01*
G01Y442126D01*
G03X346457Y450000I-7874J0D01*
G01X336614D01*
G02X334646Y451969I0J1969D01*
G01Y469024D01*
X331764Y474016D01*
X314921D01*
X311969Y471063D01*
Y451969D01*
G02X310000Y450000I-1969J0D01*
G01X304094D01*
G02X302126Y451969I1J1969D01*
G01Y471063D01*
X299173Y474016D01*
X265886D01*
X262933Y471063D01*
Y450886D01*
G02X254075I-4429J0D01*
G01Y471063D01*
X251122Y474016D01*
X184783D01*
X181831Y471063D01*
Y450098D01*
G02X174547I-3642J0D01*
G01Y471063D01*
X171594Y474016D01*
X138287D01*
X135335Y471063D01*
Y451870D01*
G02X124508I-5413J0D01*
G01Y471063D01*
X121555Y474016D01*
X55177D01*
X52224Y471063D01*
Y451969D01*
G02X50256Y450000I-1969J0D01*
G01X44350D01*
G02X42382Y451969I0J1969D01*
G01Y471063D01*
X39429Y474016D01*
X22567D01*
X19685Y469024D01*
Y451969D01*
G02X17717Y450000I-1969J0D01*
G01X7874D01*
G01X28346Y46417D02*
G02X15748I-6299J0D01*
G02X28346I6299J0D01*
G01X15748D02*
G02X28346I6299J0D01*
G02X15748I-6299J0D01*
G01D02*
G02X28346I6299J0D01*
G02X15748I-6299J0D01*
G01X30177Y89331D02*
G02X17854I-6161J0D01*
G02X30177I6162J0D01*
G01X17854D02*
G02X30177I6162J0D01*
G02X17854I-6161J0D01*
G01D02*
G02X30177I6162J0D01*
G02X17854I-6161J0D01*
G01X111614Y189721D02*
Y183422D01*
G02X99016I-6299J0D01*
G01Y189721D01*
G02X111614I6299J0D01*
G01X99016D02*
G02X111614I6299J0D01*
G01Y183422D01*
G02X99016I-6299J0D01*
G01Y189721D01*
G01D02*
Y183422D01*
G03X111614I6299J0D01*
G01Y189721D01*
G03X99016I-6299J0D01*
G01X97835Y213343D02*
G02X112795I7480J0D01*
G02X97835I-7480J0D01*
G01X112795D02*
G02X97835I-7480J0D01*
G02X112795I7480J0D01*
G01D02*
G03X97835I-7480J0D01*
G03X112795I7480J0D01*
G01X141693Y-609436D02*
Y-684436D01*
G01Y-659436D02*
X244693D01*
Y-634436D01*
G01X141693D02*
X244693D01*
G01X242913Y424016D02*
G02X229528I-6693J0D01*
G02X242913I6692J0D01*
G01X229528D02*
G02X242913I6692J0D01*
G02X229528I-6693J0D01*
G01D02*
G02X242913I6692J0D01*
G02X229528I-6693J0D01*
G01X246693Y-609436D02*
Y-684436D01*
G01X244693Y-609436D02*
Y-684436D01*
G01X252200Y-669436D02*
Y-664436D01*
X253466D01*
X253973Y-664686D01*
X254353Y-665019D01*
X254670Y-665519D01*
X254923Y-666103D01*
X254986Y-666936D01*
X254923Y-667769D01*
X254670Y-668353D01*
X254353Y-668853D01*
X253973Y-669186D01*
X253466Y-669436D01*
X252200D01*
G01X257110D02*
X258693Y-664436D01*
X260276Y-669436D01*
G01X259706Y-667686D02*
X257680D01*
G01X263793Y-664436D02*
Y-669436D01*
G01X262336Y-664436D02*
X265250D01*
G01X270160Y-669436D02*
X267626D01*
Y-664436D01*
X270160D01*
G01X269146Y-666853D02*
X267626D01*
G01X273993Y-669603D02*
X273866Y-669519D01*
Y-669353D01*
X273993Y-669269D01*
X274120Y-669353D01*
Y-669519D01*
X273993Y-669603D01*
G01Y-667353D02*
X273866Y-667269D01*
Y-667103D01*
X273993Y-667019D01*
X274120Y-667103D01*
Y-667269D01*
X273993Y-667353D01*
G01X246693Y-659436D02*
X446693D01*
G01X252326Y-644436D02*
Y-639436D01*
X253846D01*
X254353Y-639686D01*
X254733Y-640269D01*
X254860Y-640936D01*
X254733Y-641603D01*
X254416Y-642103D01*
X253846Y-642353D01*
X252326D01*
G01X257553Y-644603D02*
X259833Y-639436D01*
G01X262336Y-644436D02*
Y-639436D01*
X265250Y-644436D01*
Y-639436D01*
G01X268893Y-644603D02*
X268766Y-644519D01*
Y-644353D01*
X268893Y-644269D01*
X269020Y-644353D01*
Y-644519D01*
X268893Y-644603D01*
G01Y-642353D02*
X268766Y-642269D01*
Y-642103D01*
X268893Y-642019D01*
X269020Y-642103D01*
Y-642269D01*
X268893Y-642353D01*
G01X246693Y-634436D02*
X446693D01*
G01X252326Y-619436D02*
Y-614436D01*
X253846D01*
X254353Y-614686D01*
X254733Y-615269D01*
X254860Y-615936D01*
X254733Y-616603D01*
X254416Y-617103D01*
X253846Y-617353D01*
X252326D01*
G01X257426Y-619436D02*
Y-614436D01*
X259010D01*
X259516Y-614686D01*
X259833Y-615019D01*
X259960Y-615686D01*
X259833Y-616353D01*
X259453Y-616769D01*
X259010Y-617019D01*
X257426D01*
G01X259010D02*
X259960Y-619436D01*
G01X263793D02*
X263286Y-619353D01*
X262843Y-619019D01*
X262463Y-618519D01*
X262210Y-617936D01*
X262083Y-617269D01*
Y-616603D01*
X262210Y-615936D01*
X262463Y-615353D01*
X262843Y-614853D01*
X263286Y-614519D01*
X263793Y-614436D01*
X264300Y-614519D01*
X264743Y-614853D01*
X265123Y-615353D01*
X265376Y-615936D01*
X265503Y-616603D01*
Y-617269D01*
X265376Y-617936D01*
X265123Y-618519D01*
X264743Y-619019D01*
X264300Y-619353D01*
X263793Y-619436D01*
G01X267626Y-618436D02*
X267943Y-618936D01*
X268323Y-619269D01*
X268766Y-619436D01*
X269273Y-619269D01*
X269653Y-618936D01*
X270033Y-618436D01*
X270160Y-617769D01*
Y-614436D01*
G01X275260Y-619436D02*
X272726D01*
Y-614436D01*
X275260D01*
G01X274246Y-616853D02*
X272726D01*
G01X280486Y-614853D02*
X280106Y-614603D01*
X279663Y-614436D01*
X279156D01*
X278586Y-614686D01*
X278143Y-615103D01*
X277826Y-615603D01*
X277573Y-616436D01*
X277510Y-617186D01*
X277636Y-617936D01*
X277826Y-618436D01*
X278206Y-618936D01*
X278650Y-619269D01*
X279093Y-619436D01*
X279536D01*
X279980Y-619269D01*
X280360Y-619019D01*
X280676Y-618686D01*
G01X284193Y-614436D02*
Y-619436D01*
G01X282736Y-614436D02*
X285650D01*
G01X289293Y-619603D02*
X289166Y-619519D01*
Y-619353D01*
X289293Y-619269D01*
X289420Y-619353D01*
Y-619519D01*
X289293Y-619603D01*
G01Y-617353D02*
X289166Y-617269D01*
Y-617103D01*
X289293Y-617019D01*
X289420Y-617103D01*
Y-617269D01*
X289293Y-617353D01*
G01X307874Y424016D02*
G02X294488I-6693J0D01*
G02X307874I6693J0D01*
G01X294488D02*
G02X307874I6693J0D01*
G02X294488I-6693J0D01*
G01D02*
G02X307874I6693J0D01*
G02X294488I-6693J0D01*
G01X339764Y46417D02*
G02X327165I-6299J0D01*
G02X339764I6299J0D01*
G01X327165D02*
G02X339764I6299J0D01*
G02X327165I-6299J0D01*
G01D02*
G02X339764I6299J0D01*
G02X327165I-6299J0D01*
G01X336476Y89331D02*
G02X324154I-6161J0D01*
G02X336476I6161J0D01*
G01X324154D02*
G02X336476I6161J0D01*
G02X324154I-6161J0D01*
G01D02*
G02X336476I6161J0D01*
G02X324154I-6161J0D01*
G01X361693Y-659436D02*
Y-684436D01*
G01X364326Y-661936D02*
Y-666936D01*
X366860D01*
G01X369933Y-661936D02*
X371453D01*
G01X370693D02*
Y-666936D01*
G01X369933D02*
X371453D01*
G01X376300Y-664269D02*
X376553Y-664019D01*
X376743Y-663603D01*
X376870Y-663019D01*
X376743Y-662519D01*
X376490Y-662186D01*
X376046Y-661936D01*
X374336D01*
Y-666936D01*
X376426D01*
X376870Y-666603D01*
X377123Y-666103D01*
X377250Y-665519D01*
X377123Y-664936D01*
X376743Y-664436D01*
X376300Y-664269D01*
X374336D01*
G01X380893Y-667103D02*
X380766Y-667019D01*
Y-666853D01*
X380893Y-666769D01*
X381020Y-666853D01*
Y-667019D01*
X380893Y-667103D01*
G01Y-664853D02*
X380766Y-664769D01*
Y-664603D01*
X380893Y-664519D01*
X381020Y-664603D01*
Y-664769D01*
X380893Y-664853D01*
G01X404693Y-659436D02*
Y-684436D01*
G01Y-634436D02*
Y-659436D01*
G01X412706Y-687603D02*
X412813Y-687478D01*
X412893Y-687269D01*
X412946Y-686978D01*
X412893Y-686728D01*
X412786Y-686561D01*
X412600Y-686436D01*
X411880D01*
Y-688936D01*
X412760D01*
X412946Y-688769D01*
X413053Y-688519D01*
X413106Y-688228D01*
X413053Y-687936D01*
X412893Y-687686D01*
X412706Y-687603D01*
X411880D01*
G01X415173Y-688936D02*
Y-687269D01*
G01Y-687561D02*
X415066Y-687394D01*
X414906Y-687311D01*
X414720Y-687269D01*
X414533Y-687353D01*
X414373Y-687519D01*
X414266Y-687769D01*
X414213Y-688103D01*
X414266Y-688436D01*
X414373Y-688686D01*
X414533Y-688853D01*
X414720Y-688936D01*
X414906Y-688894D01*
X415066Y-688769D01*
X415173Y-688603D01*
G01X416493Y-688644D02*
X416626Y-688811D01*
X416813Y-688936D01*
X416973D01*
X417133Y-688853D01*
X417240Y-688728D01*
X417293Y-688561D01*
X417266Y-688311D01*
X417160Y-688186D01*
X416680Y-687936D01*
X416573Y-687644D01*
X416626Y-687436D01*
X416733Y-687311D01*
X416893Y-687269D01*
X417053Y-687311D01*
X417213Y-687436D01*
G01X418693Y-687811D02*
X419546D01*
X419466Y-687519D01*
X419333Y-687353D01*
X419146Y-687269D01*
X418960Y-687311D01*
X418800Y-687436D01*
X418693Y-687728D01*
X418640Y-687978D01*
Y-688228D01*
X418693Y-688478D01*
X418826Y-688728D01*
X418986Y-688894D01*
X419173Y-688936D01*
X419360Y-688853D01*
X419546Y-688603D01*
G01X420813Y-688936D02*
Y-686436D01*
G01Y-687686D02*
X420946Y-687436D01*
X421106Y-687311D01*
X421266Y-687269D01*
X421506Y-687353D01*
X421666Y-687519D01*
X421773Y-687811D01*
Y-688144D01*
X421720Y-688478D01*
X421613Y-688728D01*
X421426Y-688894D01*
X421266Y-688936D01*
X421106Y-688894D01*
X420946Y-688769D01*
X420813Y-688561D01*
G01X423493Y-688936D02*
X423333Y-688894D01*
X423173Y-688728D01*
X423066Y-688436D01*
X423013Y-688103D01*
X423066Y-687769D01*
X423173Y-687478D01*
X423333Y-687311D01*
X423493Y-687269D01*
X423653Y-687311D01*
X423813Y-687478D01*
X423920Y-687769D01*
X423946Y-688103D01*
X423920Y-688436D01*
X423813Y-688728D01*
X423653Y-688894D01*
X423493Y-688936D01*
G01X426173D02*
Y-687269D01*
G01Y-687561D02*
X426066Y-687394D01*
X425906Y-687311D01*
X425720Y-687269D01*
X425533Y-687353D01*
X425373Y-687519D01*
X425266Y-687769D01*
X425213Y-688103D01*
X425266Y-688436D01*
X425373Y-688686D01*
X425533Y-688853D01*
X425720Y-688936D01*
X425906Y-688894D01*
X426066Y-688769D01*
X426173Y-688603D01*
G01X427520Y-688936D02*
Y-687269D01*
G01Y-687603D02*
X427653Y-687436D01*
X427786Y-687311D01*
X427973Y-687269D01*
X428106Y-687311D01*
X428266Y-687436D01*
G01X430573Y-686436D02*
Y-688936D01*
G01Y-688561D02*
X430466Y-688769D01*
X430306Y-688894D01*
X430120Y-688936D01*
X429906Y-688853D01*
X429746Y-688644D01*
X429640Y-688394D01*
X429613Y-688103D01*
X429640Y-687811D01*
X429746Y-687561D01*
X429906Y-687353D01*
X430120Y-687269D01*
X430306Y-687311D01*
X430440Y-687394D01*
X430573Y-687561D01*
G01X433960Y-688936D02*
Y-686436D01*
X434626D01*
X434840Y-686561D01*
X434973Y-686728D01*
X435026Y-687061D01*
X434973Y-687394D01*
X434813Y-687603D01*
X434626Y-687728D01*
X433960D01*
G01X434626D02*
X435026Y-688936D01*
G01X436293Y-687811D02*
X437146D01*
X437066Y-687519D01*
X436933Y-687353D01*
X436746Y-687269D01*
X436560Y-687311D01*
X436400Y-687436D01*
X436293Y-687728D01*
X436240Y-687978D01*
Y-688228D01*
X436293Y-688478D01*
X436426Y-688728D01*
X436586Y-688894D01*
X436773Y-688936D01*
X436960Y-688853D01*
X437146Y-688603D01*
G01X438413Y-687269D02*
X438893Y-688936D01*
X439373Y-687269D01*
G01X441093Y-689019D02*
X441040Y-688978D01*
Y-688894D01*
X441093Y-688853D01*
X441146Y-688894D01*
Y-688978D01*
X441093Y-689019D01*
G01X443613Y-688936D02*
Y-686436D01*
X442626Y-688228D01*
X443960D01*
G01X444826Y-688936D02*
X445493Y-686436D01*
X446160Y-688936D01*
G01X445920Y-688061D02*
X445066D01*
G01X408593Y-661936D02*
Y-666936D01*
G01X407136Y-661936D02*
X410050D01*
G01X413693Y-666936D02*
X413313Y-666853D01*
X412933Y-666519D01*
X412680Y-665936D01*
X412553Y-665269D01*
X412680Y-664603D01*
X412933Y-664019D01*
X413313Y-663686D01*
X413693Y-663603D01*
X414073Y-663686D01*
X414453Y-664019D01*
X414706Y-664603D01*
X414770Y-665269D01*
X414706Y-665936D01*
X414453Y-666519D01*
X414073Y-666853D01*
X413693Y-666936D01*
G01X418793D02*
X418413Y-666853D01*
X418033Y-666519D01*
X417780Y-665936D01*
X417653Y-665269D01*
X417780Y-664603D01*
X418033Y-664019D01*
X418413Y-663686D01*
X418793Y-663603D01*
X419173Y-663686D01*
X419553Y-664019D01*
X419806Y-664603D01*
X419870Y-665269D01*
X419806Y-665936D01*
X419553Y-666519D01*
X419173Y-666853D01*
X418793Y-666936D01*
G01X423893D02*
Y-661936D01*
G01X428993Y-667103D02*
X428866Y-667019D01*
Y-666853D01*
X428993Y-666769D01*
X429120Y-666853D01*
Y-667019D01*
X428993Y-667103D01*
G01Y-664853D02*
X428866Y-664769D01*
Y-664603D01*
X428993Y-664519D01*
X429120Y-664603D01*
Y-664769D01*
X428993Y-664853D01*
G01X407326Y-641936D02*
Y-636936D01*
X408910D01*
X409416Y-637186D01*
X409733Y-637519D01*
X409860Y-638186D01*
X409733Y-638853D01*
X409353Y-639269D01*
X408910Y-639519D01*
X407326D01*
G01X408910D02*
X409860Y-641936D01*
G01X414960D02*
X412426D01*
Y-636936D01*
X414960D01*
G01X413946Y-639353D02*
X412426D01*
G01X417210Y-636936D02*
X418793Y-641936D01*
X420376Y-636936D01*
G01X423893Y-642103D02*
X423766Y-642019D01*
Y-641853D01*
X423893Y-641769D01*
X424020Y-641853D01*
Y-642019D01*
X423893Y-642103D01*
G01Y-639853D02*
X423766Y-639769D01*
Y-639603D01*
X423893Y-639519D01*
X424020Y-639603D01*
Y-639769D01*
X423893Y-639853D01*
G01X2010999Y-388000D02*
Y1475775D01*
X-407000D01*
Y-386798D01*
Y-755294D01*
Y-793716D01*
X-368578D01*
X1942346D01*
X2010999D01*
Y-725063D01*
Y-388000D01*
G01X-65401Y-467252D02*
Y-464152D01*
X-64481D01*
X-64174Y-464307D01*
X-63944Y-464669D01*
X-63867Y-465082D01*
X-63944Y-465495D01*
X-64136Y-465805D01*
X-64481Y-465960D01*
X-65401D01*
G01X-62224Y-467355D02*
X-60844Y-464152D01*
G01X-59316Y-467252D02*
Y-464152D01*
X-57552Y-467252D01*
Y-464152D01*
G01X-55334Y-467355D02*
X-55411Y-467304D01*
Y-467200D01*
X-55334Y-467149D01*
X-55257Y-467200D01*
Y-467304D01*
X-55334Y-467355D01*
G01Y-465960D02*
X-55411Y-465909D01*
Y-465805D01*
X-55334Y-465754D01*
X-55257Y-465805D01*
Y-465909D01*
X-55334Y-465960D01*
G01X-53077Y-467252D02*
Y-464152D01*
X-52311D01*
X-52004Y-464307D01*
X-51774Y-464514D01*
X-51582Y-464824D01*
X-51429Y-465185D01*
X-51391Y-465702D01*
X-51429Y-466219D01*
X-51582Y-466580D01*
X-51774Y-466890D01*
X-52004Y-467097D01*
X-52311Y-467252D01*
X-53077D01*
G01X-50092D02*
X-49134Y-464152D01*
X-48176Y-467252D01*
G01X-48521Y-466167D02*
X-49747D01*
G01X-46034Y-464152D02*
X-46341Y-464255D01*
X-46571Y-464514D01*
X-46724Y-464824D01*
X-46839Y-465237D01*
X-46877Y-465702D01*
X-46839Y-466167D01*
X-46724Y-466580D01*
X-46571Y-466890D01*
X-46341Y-467149D01*
X-46034Y-467252D01*
X-45727Y-467149D01*
X-45497Y-466890D01*
X-45344Y-466580D01*
X-45229Y-466167D01*
X-45191Y-465702D01*
X-45229Y-465237D01*
X-45344Y-464824D01*
X-45497Y-464514D01*
X-45727Y-464255D01*
X-46034Y-464152D01*
G01X-43662Y-467252D02*
Y-464152D01*
X-42206D01*
G01X-42742Y-465650D02*
X-43662D01*
G01X-39834Y-464152D02*
X-40141Y-464255D01*
X-40371Y-464514D01*
X-40524Y-464824D01*
X-40639Y-465237D01*
X-40677Y-465702D01*
X-40639Y-466167D01*
X-40524Y-466580D01*
X-40371Y-466890D01*
X-40141Y-467149D01*
X-39834Y-467252D01*
X-39527Y-467149D01*
X-39297Y-466890D01*
X-39144Y-466580D01*
X-39029Y-466167D01*
X-38991Y-465702D01*
X-39029Y-465237D01*
X-39144Y-464824D01*
X-39297Y-464514D01*
X-39527Y-464255D01*
X-39834Y-464152D01*
G01X-36734D02*
Y-467252D01*
G01X-37616Y-464152D02*
X-35852D01*
G01X-34631Y-467252D02*
Y-464152D01*
X-33634Y-466735D01*
X-32637Y-464152D01*
Y-467252D01*
G01X-31377D02*
Y-464152D01*
X-30611D01*
X-30304Y-464307D01*
X-30074Y-464514D01*
X-29882Y-464824D01*
X-29729Y-465185D01*
X-29691Y-465702D01*
X-29729Y-466219D01*
X-29882Y-466580D01*
X-30074Y-466890D01*
X-30304Y-467097D01*
X-30611Y-467252D01*
X-31377D01*
G01X-26591Y-464410D02*
X-26821Y-464255D01*
X-27089Y-464152D01*
X-27396D01*
X-27741Y-464307D01*
X-28009Y-464565D01*
X-28201Y-464875D01*
X-28354Y-465392D01*
X-28392Y-465857D01*
X-28316Y-466322D01*
X-28201Y-466632D01*
X-27971Y-466942D01*
X-27702Y-467149D01*
X-27434Y-467252D01*
X-27166D01*
X-26897Y-467149D01*
X-26667Y-466994D01*
X-26476Y-466787D01*
G01X-25177Y-467252D02*
Y-464152D01*
X-24411D01*
X-24104Y-464307D01*
X-23874Y-464514D01*
X-23682Y-464824D01*
X-23529Y-465185D01*
X-23491Y-465702D01*
X-23529Y-466219D01*
X-23682Y-466580D01*
X-23874Y-466890D01*
X-24104Y-467097D01*
X-24411Y-467252D01*
X-25177D01*
G01X-21234Y-464152D02*
X-21541Y-464255D01*
X-21771Y-464514D01*
X-21924Y-464824D01*
X-22039Y-465237D01*
X-22077Y-465702D01*
X-22039Y-466167D01*
X-21924Y-466580D01*
X-21771Y-466890D01*
X-21541Y-467149D01*
X-21234Y-467252D01*
X-20927Y-467149D01*
X-20697Y-466890D01*
X-20544Y-466580D01*
X-20429Y-466167D01*
X-20391Y-465702D01*
X-20429Y-465237D01*
X-20544Y-464824D01*
X-20697Y-464514D01*
X-20927Y-464255D01*
X-21234Y-464152D01*
G01X-65015Y6046D02*
Y9146D01*
X-64095D01*
X-63788Y8991D01*
X-63558Y8629D01*
X-63481Y8216D01*
X-63558Y7803D01*
X-63750Y7493D01*
X-64095Y7338D01*
X-65015D01*
G01X-61838Y5943D02*
X-60458Y9146D01*
G01X-58930Y6046D02*
Y9146D01*
X-57166Y6046D01*
Y9146D01*
G01X-54948Y5943D02*
X-55025Y5994D01*
Y6098D01*
X-54948Y6149D01*
X-54871Y6098D01*
Y5994D01*
X-54948Y5943D01*
G01Y7338D02*
X-55025Y7389D01*
Y7493D01*
X-54948Y7544D01*
X-54871Y7493D01*
Y7389D01*
X-54948Y7338D01*
G01X-52691Y6046D02*
Y9146D01*
X-51925D01*
X-51618Y8991D01*
X-51388Y8784D01*
X-51196Y8474D01*
X-51043Y8113D01*
X-51005Y7596D01*
X-51043Y7079D01*
X-51196Y6718D01*
X-51388Y6408D01*
X-51618Y6201D01*
X-51925Y6046D01*
X-52691D01*
G01X-49706D02*
X-48748Y9146D01*
X-47790Y6046D01*
G01X-48135Y7131D02*
X-49361D01*
G01X-45648Y9146D02*
X-45955Y9043D01*
X-46185Y8784D01*
X-46338Y8474D01*
X-46453Y8061D01*
X-46491Y7596D01*
X-46453Y7131D01*
X-46338Y6718D01*
X-46185Y6408D01*
X-45955Y6149D01*
X-45648Y6046D01*
X-45341Y6149D01*
X-45111Y6408D01*
X-44958Y6718D01*
X-44843Y7131D01*
X-44805Y7596D01*
X-44843Y8061D01*
X-44958Y8474D01*
X-45111Y8784D01*
X-45341Y9043D01*
X-45648Y9146D01*
G01X-43276Y6046D02*
Y9146D01*
X-41820D01*
G01X-42356Y7648D02*
X-43276D01*
G01X-39448Y9146D02*
X-39755Y9043D01*
X-39985Y8784D01*
X-40138Y8474D01*
X-40253Y8061D01*
X-40291Y7596D01*
X-40253Y7131D01*
X-40138Y6718D01*
X-39985Y6408D01*
X-39755Y6149D01*
X-39448Y6046D01*
X-39141Y6149D01*
X-38911Y6408D01*
X-38758Y6718D01*
X-38643Y7131D01*
X-38605Y7596D01*
X-38643Y8061D01*
X-38758Y8474D01*
X-38911Y8784D01*
X-39141Y9043D01*
X-39448Y9146D01*
G01X-36348D02*
Y6046D01*
G01X-37230Y9146D02*
X-35466D01*
G01X-34245Y6046D02*
Y9146D01*
X-33248Y6563D01*
X-32251Y9146D01*
Y6046D01*
G01X-30991D02*
Y9146D01*
X-30225D01*
X-29918Y8991D01*
X-29688Y8784D01*
X-29496Y8474D01*
X-29343Y8113D01*
X-29305Y7596D01*
X-29343Y7079D01*
X-29496Y6718D01*
X-29688Y6408D01*
X-29918Y6201D01*
X-30225Y6046D01*
X-30991D01*
G01X-26205Y8888D02*
X-26435Y9043D01*
X-26703Y9146D01*
X-27010D01*
X-27355Y8991D01*
X-27623Y8733D01*
X-27815Y8423D01*
X-27968Y7906D01*
X-28006Y7441D01*
X-27930Y6976D01*
X-27815Y6666D01*
X-27585Y6356D01*
X-27316Y6149D01*
X-27048Y6046D01*
X-26780D01*
X-26511Y6149D01*
X-26281Y6304D01*
X-26090Y6511D01*
G01X-24791Y6046D02*
Y9146D01*
X-24025D01*
X-23718Y8991D01*
X-23488Y8784D01*
X-23296Y8474D01*
X-23143Y8113D01*
X-23105Y7596D01*
X-23143Y7079D01*
X-23296Y6718D01*
X-23488Y6408D01*
X-23718Y6201D01*
X-24025Y6046D01*
X-24791D01*
G01X-20848Y9146D02*
X-21155Y9043D01*
X-21385Y8784D01*
X-21538Y8474D01*
X-21653Y8061D01*
X-21691Y7596D01*
X-21653Y7131D01*
X-21538Y6718D01*
X-21385Y6408D01*
X-21155Y6149D01*
X-20848Y6046D01*
X-20541Y6149D01*
X-20311Y6408D01*
X-20158Y6718D01*
X-20043Y7131D01*
X-20005Y7596D01*
X-20043Y8061D01*
X-20158Y8474D01*
X-20311Y8784D01*
X-20541Y9043D01*
X-20848Y9146D01*
G01X-63888Y22036D02*
Y25136D01*
X-62968D01*
X-62661Y24981D01*
X-62431Y24619D01*
X-62354Y24206D01*
X-62431Y23793D01*
X-62623Y23483D01*
X-62968Y23328D01*
X-63888D01*
G01X-60711Y21933D02*
X-59331Y25136D01*
G01X-57803Y22036D02*
Y25136D01*
X-56039Y22036D01*
Y25136D01*
G01X-53821Y21933D02*
X-53898Y21984D01*
Y22088D01*
X-53821Y22139D01*
X-53744Y22088D01*
Y21984D01*
X-53821Y21933D01*
G01Y23328D02*
X-53898Y23379D01*
Y23483D01*
X-53821Y23534D01*
X-53744Y23483D01*
Y23379D01*
X-53821Y23328D01*
G01X-51564Y22036D02*
Y25136D01*
X-50798D01*
X-50491Y24981D01*
X-50261Y24774D01*
X-50069Y24464D01*
X-49916Y24103D01*
X-49878Y23586D01*
X-49916Y23069D01*
X-50069Y22708D01*
X-50261Y22398D01*
X-50491Y22191D01*
X-50798Y22036D01*
X-51564D01*
G01X-48579D02*
X-47621Y25136D01*
X-46663Y22036D01*
G01X-47008Y23121D02*
X-48234D01*
G01X-44521Y25136D02*
X-44828Y25033D01*
X-45058Y24774D01*
X-45211Y24464D01*
X-45326Y24051D01*
X-45364Y23586D01*
X-45326Y23121D01*
X-45211Y22708D01*
X-45058Y22398D01*
X-44828Y22139D01*
X-44521Y22036D01*
X-44214Y22139D01*
X-43984Y22398D01*
X-43831Y22708D01*
X-43716Y23121D01*
X-43678Y23586D01*
X-43716Y24051D01*
X-43831Y24464D01*
X-43984Y24774D01*
X-44214Y25033D01*
X-44521Y25136D01*
G01X-42149Y22036D02*
Y25136D01*
X-40693D01*
G01X-41229Y23638D02*
X-42149D01*
G01X-38321Y25136D02*
X-38628Y25033D01*
X-38858Y24774D01*
X-39011Y24464D01*
X-39126Y24051D01*
X-39164Y23586D01*
X-39126Y23121D01*
X-39011Y22708D01*
X-38858Y22398D01*
X-38628Y22139D01*
X-38321Y22036D01*
X-38014Y22139D01*
X-37784Y22398D01*
X-37631Y22708D01*
X-37516Y23121D01*
X-37478Y23586D01*
X-37516Y24051D01*
X-37631Y24464D01*
X-37784Y24774D01*
X-38014Y25033D01*
X-38321Y25136D01*
G01X-35221D02*
Y22036D01*
G01X-36103Y25136D02*
X-34339D01*
G01X-33118Y22036D02*
Y25136D01*
X-32121Y22553D01*
X-31124Y25136D01*
Y22036D01*
G01X-29864D02*
Y25136D01*
X-29098D01*
X-28791Y24981D01*
X-28561Y24774D01*
X-28369Y24464D01*
X-28216Y24103D01*
X-28178Y23586D01*
X-28216Y23069D01*
X-28369Y22708D01*
X-28561Y22398D01*
X-28791Y22191D01*
X-29098Y22036D01*
X-29864D01*
G01X-25078Y24878D02*
X-25308Y25033D01*
X-25576Y25136D01*
X-25883D01*
X-26228Y24981D01*
X-26496Y24723D01*
X-26688Y24413D01*
X-26841Y23896D01*
X-26879Y23431D01*
X-26803Y22966D01*
X-26688Y22656D01*
X-26458Y22346D01*
X-26189Y22139D01*
X-25921Y22036D01*
X-25653D01*
X-25384Y22139D01*
X-25154Y22294D01*
X-24963Y22501D01*
G01X-23664Y22036D02*
Y25136D01*
X-22898D01*
X-22591Y24981D01*
X-22361Y24774D01*
X-22169Y24464D01*
X-22016Y24103D01*
X-21978Y23586D01*
X-22016Y23069D01*
X-22169Y22708D01*
X-22361Y22398D01*
X-22591Y22191D01*
X-22898Y22036D01*
X-23664D01*
G01X-19721Y25136D02*
X-20028Y25033D01*
X-20258Y24774D01*
X-20411Y24464D01*
X-20526Y24051D01*
X-20564Y23586D01*
X-20526Y23121D01*
X-20411Y22708D01*
X-20258Y22398D01*
X-20028Y22139D01*
X-19721Y22036D01*
X-19414Y22139D01*
X-19184Y22398D01*
X-19031Y22708D01*
X-18916Y23121D01*
X-18878Y23586D01*
X-18916Y24051D01*
X-19031Y24464D01*
X-19184Y24774D01*
X-19414Y25033D01*
X-19721Y25136D01*
G01X-69822Y61792D02*
X-43596D01*
X-56709Y27216D01*
X-69822Y61792D01*
G01X-70202Y63475D02*
Y66575D01*
X-69436D01*
X-69129Y66420D01*
X-68899Y66213D01*
X-68707Y65903D01*
X-68554Y65542D01*
X-68516Y65025D01*
X-68554Y64508D01*
X-68707Y64147D01*
X-68899Y63837D01*
X-69129Y63630D01*
X-69436Y63475D01*
X-70202D01*
G01X-65952Y65128D02*
X-65799Y65283D01*
X-65684Y65542D01*
X-65607Y65903D01*
X-65684Y66213D01*
X-65837Y66420D01*
X-66106Y66575D01*
X-67141D01*
Y63475D01*
X-65876D01*
X-65607Y63682D01*
X-65454Y63992D01*
X-65377Y64353D01*
X-65454Y64715D01*
X-65684Y65025D01*
X-65952Y65128D01*
X-67141D01*
G01X-64002Y63940D02*
X-63772Y63682D01*
X-63504Y63527D01*
X-63159Y63475D01*
X-62814Y63578D01*
X-62546Y63785D01*
X-62354Y64147D01*
X-62316Y64560D01*
X-62392Y64973D01*
X-62584Y65232D01*
X-62852Y65438D01*
X-63121Y65490D01*
X-63389Y65438D01*
X-63734Y65232D01*
X-63619Y66575D01*
X-62584D01*
G01X-42602Y-671096D02*
X-41975Y-671621D01*
X-41270Y-671936D01*
X-40644D01*
X-40017Y-671621D01*
X-39547Y-671096D01*
X-39312Y-670361D01*
X-39469Y-669626D01*
X-39860Y-668996D01*
X-40565Y-668576D01*
X-41505Y-668366D01*
X-42054Y-667946D01*
X-42289Y-667211D01*
X-42132Y-666476D01*
X-41740Y-665951D01*
X-41192Y-665636D01*
X-40644D01*
X-40095Y-665846D01*
X-39625Y-666371D01*
G01X-36302Y-671936D02*
Y-665636D01*
G01X-33012D02*
Y-671936D01*
G01Y-668786D02*
X-36302D01*
G01X-29297Y-665636D02*
X-27417D01*
G01X-28357D02*
Y-671936D01*
G01X-29297D02*
X-27417D01*
G01X-20490D02*
X-23624D01*
Y-665636D01*
X-20490D01*
G01X-21744Y-668681D02*
X-23624D01*
G01X-17559Y-671936D02*
Y-665636D01*
X-13955Y-671936D01*
Y-665636D01*
G01X-9614Y-673091D02*
X-9300Y-671726D01*
G01X-3157Y-665636D02*
Y-671936D01*
G01X-4959Y-665636D02*
X-1355D01*
G01X1185Y-671936D02*
X3143Y-665636D01*
X5101Y-671936D01*
G01X4396Y-669731D02*
X1890D01*
G01X8503Y-665636D02*
X10383D01*
G01X9443D02*
Y-671936D01*
G01X8503D02*
X10383D01*
G01X13393Y-665636D02*
X14490Y-671936D01*
X15743Y-665636D01*
X16996Y-671936D01*
X18093Y-665636D01*
G01X20085Y-671936D02*
X22043Y-665636D01*
X24001Y-671936D01*
G01X23296Y-669731D02*
X20790D01*
G01X26541Y-671936D02*
Y-665636D01*
X30145Y-671936D01*
Y-665636D01*
G01X39376Y-671936D02*
Y-665636D01*
X41335D01*
X41961Y-665951D01*
X42353Y-666371D01*
X42510Y-667211D01*
X42353Y-668051D01*
X41883Y-668576D01*
X41335Y-668891D01*
X39376D01*
G01X41335D02*
X42510Y-671936D01*
G01X47243Y-672146D02*
X47086Y-672041D01*
Y-671831D01*
X47243Y-671726D01*
X47400Y-671831D01*
Y-672041D01*
X47243Y-672146D01*
G01X53543Y-671936D02*
X52916Y-671831D01*
X52368Y-671411D01*
X51898Y-670781D01*
X51585Y-670046D01*
X51428Y-669206D01*
Y-668366D01*
X51585Y-667526D01*
X51898Y-666791D01*
X52368Y-666161D01*
X52916Y-665741D01*
X53543Y-665636D01*
X54170Y-665741D01*
X54718Y-666161D01*
X55188Y-666791D01*
X55501Y-667526D01*
X55658Y-668366D01*
Y-669206D01*
X55501Y-670046D01*
X55188Y-670781D01*
X54718Y-671411D01*
X54170Y-671831D01*
X53543Y-671936D01*
G01X59843Y-672146D02*
X59686Y-672041D01*
Y-671831D01*
X59843Y-671726D01*
X60000Y-671831D01*
Y-672041D01*
X59843Y-672146D01*
G01X67866Y-666161D02*
X67396Y-665846D01*
X66848Y-665636D01*
X66221D01*
X65516Y-665951D01*
X64968Y-666476D01*
X64576Y-667106D01*
X64263Y-668156D01*
X64185Y-669101D01*
X64341Y-670046D01*
X64576Y-670676D01*
X65046Y-671306D01*
X65595Y-671726D01*
X66143Y-671936D01*
X66691D01*
X67240Y-671726D01*
X67710Y-671411D01*
X68101Y-670991D01*
G01X72443Y-672146D02*
X72286Y-672041D01*
Y-671831D01*
X72443Y-671726D01*
X72600Y-671831D01*
Y-672041D01*
X72443Y-672146D01*
G01X-42680Y-661936D02*
Y-655636D01*
G01X-39704D02*
X-42680Y-659521D01*
G01X-39234Y-661936D02*
X-41349Y-657736D01*
G01X-36380Y-655636D02*
Y-660151D01*
X-36067Y-661096D01*
X-35440Y-661726D01*
X-34657Y-661936D01*
X-33874Y-661726D01*
X-33247Y-661096D01*
X-32934Y-660151D01*
Y-655636D01*
G01X-26790Y-661936D02*
X-29924D01*
Y-655636D01*
X-26790D01*
G01X-28044Y-658681D02*
X-29924D01*
G01X-22997Y-655636D02*
X-21117D01*
G01X-22057D02*
Y-661936D01*
G01X-22997D02*
X-21117D01*
G01X-11102Y-661096D02*
X-10475Y-661621D01*
X-9770Y-661936D01*
X-9144D01*
X-8517Y-661621D01*
X-8047Y-661096D01*
X-7812Y-660361D01*
X-7969Y-659626D01*
X-8360Y-658996D01*
X-9065Y-658576D01*
X-10005Y-658366D01*
X-10554Y-657946D01*
X-10789Y-657211D01*
X-10632Y-656476D01*
X-10240Y-655951D01*
X-9692Y-655636D01*
X-9144D01*
X-8595Y-655846D01*
X-8125Y-656371D01*
G01X-4802Y-661936D02*
Y-655636D01*
G01X-1512D02*
Y-661936D01*
G01Y-658786D02*
X-4802D01*
G01X1185Y-661936D02*
X3143Y-655636D01*
X5101Y-661936D01*
G01X4396Y-659731D02*
X1890D01*
G01X7641Y-661936D02*
Y-655636D01*
X11245Y-661936D01*
Y-655636D01*
G01X20398Y-661936D02*
Y-655636D01*
G01X23688D02*
Y-661936D01*
G01Y-658786D02*
X20398D01*
G01X26698Y-661096D02*
X27325Y-661621D01*
X28030Y-661936D01*
X28656D01*
X29283Y-661621D01*
X29753Y-661096D01*
X29988Y-660361D01*
X29831Y-659626D01*
X29440Y-658996D01*
X28735Y-658576D01*
X27795Y-658366D01*
X27246Y-657946D01*
X27011Y-657211D01*
X27168Y-656476D01*
X27560Y-655951D01*
X28108Y-655636D01*
X28656D01*
X29205Y-655846D01*
X29675Y-656371D01*
G01X33703Y-655636D02*
X35583D01*
G01X34643D02*
Y-661936D01*
G01X33703D02*
X35583D01*
G01X38985D02*
X40943Y-655636D01*
X42901Y-661936D01*
G01X42196Y-659731D02*
X39690D01*
G01X45441Y-661936D02*
Y-655636D01*
X49045Y-661936D01*
Y-655636D01*
G01X54013Y-658786D02*
X55580D01*
Y-660676D01*
X55110Y-661306D01*
X54561Y-661726D01*
X53778Y-661936D01*
X52995Y-661726D01*
X52446Y-661306D01*
X51976Y-660676D01*
X51663Y-659941D01*
X51506Y-659101D01*
Y-658366D01*
X51663Y-657736D01*
X51976Y-657001D01*
X52446Y-656371D01*
X52916Y-655951D01*
X53543Y-655636D01*
X54091D01*
X54718Y-655846D01*
X55188Y-656266D01*
G01X59686Y-663091D02*
X60000Y-661726D01*
G01X66143Y-655636D02*
Y-661936D01*
G01X64341Y-655636D02*
X67945D01*
G01X70485Y-661936D02*
X72443Y-655636D01*
X74401Y-661936D01*
G01X73696Y-659731D02*
X71190D01*
G01X78743Y-661936D02*
X78116Y-661831D01*
X77568Y-661411D01*
X77098Y-660781D01*
X76785Y-660046D01*
X76628Y-659206D01*
Y-658366D01*
X76785Y-657526D01*
X77098Y-656791D01*
X77568Y-656161D01*
X78116Y-655741D01*
X78743Y-655636D01*
X79370Y-655741D01*
X79918Y-656161D01*
X80388Y-656791D01*
X80701Y-657526D01*
X80858Y-658366D01*
Y-659206D01*
X80701Y-660046D01*
X80388Y-660781D01*
X79918Y-661411D01*
X79370Y-661831D01*
X78743Y-661936D01*
G01X91343D02*
Y-659101D01*
X89776Y-655636D01*
G01X92910D02*
X91343Y-659101D01*
G01X95920Y-655636D02*
Y-660151D01*
X96233Y-661096D01*
X96860Y-661726D01*
X97643Y-661936D01*
X98426Y-661726D01*
X99053Y-661096D01*
X99366Y-660151D01*
Y-655636D01*
G01X101985Y-661936D02*
X103943Y-655636D01*
X105901Y-661936D01*
G01X105196Y-659731D02*
X102690D01*
G01X108441Y-661936D02*
Y-655636D01*
X112045Y-661936D01*
Y-655636D01*
G01X-42759Y-651936D02*
Y-645636D01*
X-39155Y-651936D01*
Y-645636D01*
G01X-34657Y-651936D02*
X-35284Y-651831D01*
X-35832Y-651411D01*
X-36302Y-650781D01*
X-36615Y-650046D01*
X-36772Y-649206D01*
Y-648366D01*
X-36615Y-647526D01*
X-36302Y-646791D01*
X-35832Y-646161D01*
X-35284Y-645741D01*
X-34657Y-645636D01*
X-34030Y-645741D01*
X-33482Y-646161D01*
X-33012Y-646791D01*
X-32699Y-647526D01*
X-32542Y-648366D01*
Y-649206D01*
X-32699Y-650046D01*
X-33012Y-650781D01*
X-33482Y-651411D01*
X-34030Y-651831D01*
X-34657Y-651936D01*
G01X-28357Y-652146D02*
X-28514Y-652041D01*
Y-651831D01*
X-28357Y-651726D01*
X-28200Y-651831D01*
Y-652041D01*
X-28357Y-652146D01*
G01X-22057Y-651936D02*
Y-645636D01*
X-22997Y-646896D01*
G01Y-651936D02*
X-21117D01*
G01X-15757D02*
X-15209Y-651831D01*
X-14582Y-651516D01*
X-14190Y-650991D01*
X-14034Y-650256D01*
X-14190Y-649521D01*
X-14660Y-648891D01*
X-15365Y-648576D01*
X-16149D01*
X-16619Y-648366D01*
X-17010Y-647841D01*
X-17167Y-647106D01*
X-16932Y-646371D01*
X-16384Y-645846D01*
X-15757Y-645636D01*
X-15130Y-645846D01*
X-14582Y-646371D01*
X-14347Y-647106D01*
X-14504Y-647841D01*
X-14895Y-648366D01*
X-15365Y-648576D01*
X-16149D01*
X-16854Y-648891D01*
X-17324Y-649521D01*
X-17480Y-650256D01*
X-17324Y-650991D01*
X-16932Y-651516D01*
X-16305Y-651831D01*
X-15757Y-651936D01*
G01X-9457D02*
X-8909Y-651831D01*
X-8282Y-651516D01*
X-7890Y-650991D01*
X-7734Y-650256D01*
X-7890Y-649521D01*
X-8360Y-648891D01*
X-9065Y-648576D01*
X-9849D01*
X-10319Y-648366D01*
X-10710Y-647841D01*
X-10867Y-647106D01*
X-10632Y-646371D01*
X-10084Y-645846D01*
X-9457Y-645636D01*
X-8830Y-645846D01*
X-8282Y-646371D01*
X-8047Y-647106D01*
X-8204Y-647841D01*
X-8595Y-648366D01*
X-9065Y-648576D01*
X-9849D01*
X-10554Y-648891D01*
X-11024Y-649521D01*
X-11180Y-650256D01*
X-11024Y-650991D01*
X-10632Y-651516D01*
X-10005Y-651831D01*
X-9457Y-651936D01*
G01X-3314Y-653091D02*
X-3000Y-651726D01*
G01X793Y-645636D02*
X1890Y-651936D01*
X3143Y-645636D01*
X4396Y-651936D01*
X5493Y-645636D01*
G01X11010Y-651936D02*
X7876D01*
Y-645636D01*
X11010D01*
G01X9756Y-648681D02*
X7876D01*
G01X13941Y-651936D02*
Y-645636D01*
X17545Y-651936D01*
Y-645636D01*
G01X26698Y-651936D02*
Y-645636D01*
G01X29988D02*
Y-651936D01*
G01Y-648786D02*
X26698D01*
G01X32293Y-645636D02*
X33390Y-651936D01*
X34643Y-645636D01*
X35896Y-651936D01*
X36993Y-645636D01*
G01X38985Y-651936D02*
X40943Y-645636D01*
X42901Y-651936D01*
G01X42196Y-649731D02*
X39690D01*
G01X52055Y-646686D02*
X52525Y-646056D01*
X53073Y-645741D01*
X53700Y-645636D01*
X54483Y-645846D01*
X55031Y-646371D01*
X55188Y-647001D01*
X55110Y-647631D01*
X54796Y-648156D01*
X53230Y-649206D01*
X52525Y-649941D01*
X52055Y-650991D01*
X51898Y-651936D01*
X55188D01*
G01X58041D02*
Y-645636D01*
X61645Y-651936D01*
Y-645636D01*
G01X64420Y-651936D02*
Y-645636D01*
X65986D01*
X66613Y-645951D01*
X67083Y-646371D01*
X67475Y-647001D01*
X67788Y-647736D01*
X67866Y-648786D01*
X67788Y-649836D01*
X67475Y-650571D01*
X67083Y-651201D01*
X66613Y-651621D01*
X65986Y-651936D01*
X64420D01*
G01X77176D02*
Y-645636D01*
X79135D01*
X79761Y-645951D01*
X80153Y-646371D01*
X80310Y-647211D01*
X80153Y-648051D01*
X79683Y-648576D01*
X79135Y-648891D01*
X77176D01*
G01X79135D02*
X80310Y-651936D01*
G01X83320D02*
Y-645636D01*
X84886D01*
X85513Y-645951D01*
X85983Y-646371D01*
X86375Y-647001D01*
X86688Y-647736D01*
X86766Y-648786D01*
X86688Y-649836D01*
X86375Y-650571D01*
X85983Y-651201D01*
X85513Y-651621D01*
X84886Y-651936D01*
X83320D01*
G01X91343Y-652146D02*
X91186Y-652041D01*
Y-651831D01*
X91343Y-651726D01*
X91500Y-651831D01*
Y-652041D01*
X91343Y-652146D01*
G01X-43493Y63467D02*
Y66567D01*
X-42727D01*
X-42420Y66412D01*
X-42190Y66205D01*
X-41998Y65895D01*
X-41845Y65534D01*
X-41807Y65017D01*
X-41845Y64500D01*
X-41998Y64139D01*
X-42190Y63829D01*
X-42420Y63622D01*
X-42727Y63467D01*
X-43493D01*
G01X-39243Y65120D02*
X-39090Y65275D01*
X-38975Y65534D01*
X-38898Y65895D01*
X-38975Y66205D01*
X-39128Y66412D01*
X-39397Y66567D01*
X-40432D01*
Y63467D01*
X-39167D01*
X-38898Y63674D01*
X-38745Y63984D01*
X-38668Y64345D01*
X-38745Y64707D01*
X-38975Y65017D01*
X-39243Y65120D01*
X-40432D01*
G01X-37178Y64759D02*
X-36910Y65120D01*
X-36680Y65327D01*
X-36373Y65430D01*
X-36105Y65327D01*
X-35913Y65120D01*
X-35760Y64810D01*
X-35722Y64449D01*
X-35760Y64139D01*
X-35913Y63829D01*
X-36143Y63570D01*
X-36412Y63467D01*
X-36718Y63570D01*
X-36987Y63880D01*
X-37140Y64345D01*
X-37178Y64862D01*
X-37102Y65534D01*
X-36987Y65895D01*
X-36795Y66257D01*
X-36527Y66515D01*
X-36258Y66567D01*
X-35990Y66464D01*
X-35798Y66205D01*
G01X-43113Y61784D02*
X-16887D01*
X-30000Y27208D01*
X-43113Y61784D01*
G01X-16987Y244716D02*
X-43213D01*
X-30100Y279292D01*
X-16987Y244716D01*
G01X-18657Y-639236D02*
X-21177Y-638819D01*
X-23382Y-637153D01*
X-25272Y-634653D01*
X-26532Y-631736D01*
X-27162Y-628403D01*
Y-625069D01*
X-26532Y-621736D01*
X-25272Y-618819D01*
X-23382Y-616320D01*
X-21177Y-614653D01*
X-18657Y-614236D01*
X-16137Y-614653D01*
X-13932Y-616320D01*
X-12042Y-618819D01*
X-10782Y-621736D01*
X-10152Y-625069D01*
Y-628403D01*
X-10782Y-631736D01*
X-12042Y-634653D01*
X-13932Y-637153D01*
X-16137Y-638819D01*
X-18657Y-639236D01*
G01X-16137Y-632569D02*
X-12357Y-639236D01*
G01X1188Y-622570D02*
Y-634236D01*
X2448Y-637153D01*
X4338Y-638819D01*
X6543Y-639236D01*
X8748Y-638819D01*
X10638Y-637153D01*
X11898Y-634236D01*
G01Y-639236D02*
Y-622570D01*
G01X37413Y-639236D02*
Y-622570D01*
G01Y-625486D02*
X36153Y-623820D01*
X34263Y-622986D01*
X32058Y-622570D01*
X29853Y-623403D01*
X27963Y-625069D01*
X26703Y-627570D01*
X26073Y-630903D01*
X26703Y-634236D01*
X27963Y-636737D01*
X29853Y-638403D01*
X32058Y-639236D01*
X34263Y-638819D01*
X36153Y-637570D01*
X37413Y-635903D01*
G01X51588Y-639236D02*
Y-622570D01*
G01Y-626736D02*
X52848Y-624653D01*
X54738Y-622986D01*
X57258Y-622570D01*
X59463Y-622986D01*
X61353Y-624653D01*
X62298Y-627570D01*
Y-639236D01*
G01X82143Y-614236D02*
Y-639236D01*
G01X77733Y-622570D02*
X86553D01*
G01X113013Y-639236D02*
Y-622570D01*
G01Y-625486D02*
X111753Y-623820D01*
X109863Y-622986D01*
X107658Y-622570D01*
X105453Y-623403D01*
X103563Y-625069D01*
X102303Y-627570D01*
X101673Y-630903D01*
X102303Y-634236D01*
X103563Y-636737D01*
X105453Y-638403D01*
X107658Y-639236D01*
X109863Y-638819D01*
X111753Y-637570D01*
X113013Y-635903D01*
G01X-25593Y239167D02*
Y242267D01*
X-24827D01*
X-24520Y242112D01*
X-24290Y241905D01*
X-24098Y241595D01*
X-23945Y241234D01*
X-23907Y240717D01*
X-23945Y240200D01*
X-24098Y239839D01*
X-24290Y239529D01*
X-24520Y239322D01*
X-24827Y239167D01*
X-25593D01*
G01X-21343Y240820D02*
X-21190Y240975D01*
X-21075Y241234D01*
X-20998Y241595D01*
X-21075Y241905D01*
X-21228Y242112D01*
X-21497Y242267D01*
X-22532D01*
Y239167D01*
X-21267D01*
X-20998Y239374D01*
X-20845Y239684D01*
X-20768Y240045D01*
X-20845Y240407D01*
X-21075Y240717D01*
X-21343Y240820D01*
X-22532D01*
G01X-18090Y239167D02*
Y242267D01*
X-19508Y240045D01*
X-17592D01*
G01X2845Y45000D02*
Y48100D01*
G01X4455D02*
Y45000D01*
G01Y46550D02*
X2845D01*
G01X6022Y46292D02*
X6290Y46653D01*
X6520Y46860D01*
X6827Y46963D01*
X7095Y46860D01*
X7287Y46653D01*
X7440Y46343D01*
X7478Y45982D01*
X7440Y45672D01*
X7287Y45362D01*
X7057Y45103D01*
X6788Y45000D01*
X6482Y45103D01*
X6213Y45413D01*
X6060Y45878D01*
X6022Y46395D01*
X6098Y47067D01*
X6213Y47428D01*
X6405Y47790D01*
X6673Y48048D01*
X6942Y48100D01*
X7210Y47997D01*
X7402Y47738D01*
G01X2345Y61000D02*
Y64100D01*
G01X3955D02*
Y61000D01*
G01Y62550D02*
X2345D01*
G01X5522Y63583D02*
X5752Y63893D01*
X6020Y64048D01*
X6327Y64100D01*
X6710Y63997D01*
X6978Y63738D01*
X7055Y63428D01*
X7017Y63118D01*
X6863Y62860D01*
X6097Y62343D01*
X5752Y61982D01*
X5522Y61465D01*
X5445Y61000D01*
X7055D01*
G01X9657Y62653D02*
X9810Y62808D01*
X9925Y63067D01*
X10002Y63428D01*
X9925Y63738D01*
X9772Y63945D01*
X9503Y64100D01*
X8468D01*
Y61000D01*
X9733D01*
X10002Y61207D01*
X10155Y61517D01*
X10232Y61878D01*
X10155Y62240D01*
X9925Y62550D01*
X9657Y62653D01*
X8468D01*
G01X11722Y63583D02*
X11952Y63893D01*
X12220Y64048D01*
X12527Y64100D01*
X12910Y63997D01*
X13178Y63738D01*
X13255Y63428D01*
X13217Y63118D01*
X13063Y62860D01*
X12297Y62343D01*
X11952Y61982D01*
X11722Y61465D01*
X11645Y61000D01*
X13255D01*
G01X8534Y6933D02*
X5434D01*
Y7853D01*
X5589Y8160D01*
X5951Y8390D01*
X6364Y8467D01*
X6777Y8390D01*
X7087Y8198D01*
X7242Y7853D01*
Y6933D01*
G01X5434Y9650D02*
X8534Y10187D01*
X5434Y10800D01*
X8534Y11413D01*
X5434Y11950D01*
G01X8534Y13133D02*
X5434D01*
Y14092D01*
X5589Y14398D01*
X5796Y14590D01*
X6209Y14667D01*
X6622Y14590D01*
X6881Y14360D01*
X7036Y14092D01*
Y13133D01*
G01Y14092D02*
X8534Y14667D01*
G01X9567Y15850D02*
Y18150D01*
G01X6881Y20407D02*
X6726Y20560D01*
X6467Y20675D01*
X6106Y20752D01*
X5796Y20675D01*
X5589Y20522D01*
X5434Y20253D01*
Y19218D01*
X8534D01*
Y20483D01*
X8327Y20752D01*
X8017Y20905D01*
X7656Y20982D01*
X7294Y20905D01*
X6984Y20675D01*
X6881Y20407D01*
Y19218D01*
G01X5434Y23200D02*
X8534D01*
G01X5434Y22318D02*
Y24082D01*
G01X8534Y25418D02*
X5434D01*
X8534Y27182D01*
X5434D01*
G01X16929Y6065D02*
Y5473D01*
G01Y15465D02*
Y15065D01*
G01Y5473D02*
X24606D01*
Y-6338D01*
X38386D01*
Y5473D01*
X46063D01*
Y6065D01*
G01X19096Y29488D02*
X16929D01*
Y21465D01*
G01X22051Y76058D02*
G03X21204Y60979I5248J-7858D01*
G01X4645Y88450D02*
Y91550D01*
G01X6255D02*
Y88450D01*
G01Y90000D02*
X4645D01*
G01X7707Y88915D02*
X7937Y88657D01*
X8205Y88502D01*
X8550Y88450D01*
X8895Y88553D01*
X9163Y88760D01*
X9355Y89122D01*
X9393Y89535D01*
X9317Y89948D01*
X9125Y90207D01*
X8857Y90413D01*
X8588Y90465D01*
X8320Y90413D01*
X7975Y90207D01*
X8090Y91550D01*
X9125D01*
G01X22800Y118843D02*
X16200D01*
Y131843D01*
X22800D01*
Y118843D01*
G01X12130Y135993D02*
X9030D01*
Y136913D01*
X9185Y137220D01*
X9547Y137450D01*
X9960Y137527D01*
X10373Y137450D01*
X10683Y137258D01*
X10838Y136913D01*
Y135993D01*
G01X9030Y139093D02*
X12130D01*
Y140627D01*
G01X11510Y142117D02*
X11872Y142347D01*
X12078Y142653D01*
X12130Y142998D01*
X12078Y143305D01*
X11820Y143612D01*
X11510Y143803D01*
X11200Y143842D01*
X10838Y143765D01*
X10580Y143497D01*
X10477Y143228D01*
Y142883D01*
G01Y143228D02*
X10322Y143458D01*
X10063Y143650D01*
X9753Y143727D01*
X9443Y143650D01*
X9185Y143458D01*
X9030Y143113D01*
X9082Y142768D01*
X9288Y142423D01*
G01X12130Y146520D02*
X9030D01*
X11252Y145102D01*
Y147018D01*
G01X28056Y179265D02*
X14980D01*
Y135265D01*
X28156D01*
G01X16200Y125343D02*
X22800D01*
G01X15885Y182138D02*
Y185238D01*
X16805D01*
X17112Y185083D01*
X17342Y184721D01*
X17419Y184308D01*
X17342Y183895D01*
X17150Y183585D01*
X16805Y183430D01*
X15885D01*
G01X18909Y185238D02*
Y183016D01*
X19062Y182551D01*
X19369Y182241D01*
X19752Y182138D01*
X20135Y182241D01*
X20442Y182551D01*
X20595Y183016D01*
Y185238D01*
G01X22009Y182758D02*
X22239Y182396D01*
X22545Y182190D01*
X22890Y182138D01*
X23197Y182190D01*
X23504Y182448D01*
X23695Y182758D01*
X23734Y183068D01*
X23657Y183430D01*
X23389Y183688D01*
X23120Y183791D01*
X22775D01*
G01X23120D02*
X23350Y183946D01*
X23542Y184205D01*
X23619Y184515D01*
X23542Y184825D01*
X23350Y185083D01*
X23005Y185238D01*
X22660Y185186D01*
X22315Y184980D01*
G01X25952Y182138D02*
X26220Y182190D01*
X26527Y182345D01*
X26719Y182603D01*
X26795Y182965D01*
X26719Y183326D01*
X26489Y183636D01*
X26144Y183791D01*
X25760D01*
X25530Y183895D01*
X25339Y184153D01*
X25262Y184515D01*
X25377Y184876D01*
X25645Y185135D01*
X25952Y185238D01*
X26259Y185135D01*
X26527Y184876D01*
X26642Y184515D01*
X26565Y184153D01*
X26374Y183895D01*
X26144Y183791D01*
X25760D01*
X25415Y183636D01*
X25185Y183326D01*
X25109Y182965D01*
X25185Y182603D01*
X25377Y182345D01*
X25684Y182190D01*
X25952Y182138D01*
G01X13772Y184481D02*
X10672D01*
Y185401D01*
X10827Y185708D01*
X11189Y185938D01*
X11602Y186015D01*
X12015Y185938D01*
X12325Y185746D01*
X12480Y185401D01*
Y184481D01*
G01X13307Y187505D02*
X13565Y187735D01*
X13720Y188003D01*
X13772Y188348D01*
X13669Y188693D01*
X13462Y188961D01*
X13100Y189153D01*
X12687Y189191D01*
X12274Y189115D01*
X12015Y188923D01*
X11809Y188655D01*
X11757Y188386D01*
X11809Y188118D01*
X12015Y187773D01*
X10672Y187888D01*
Y188923D01*
G01Y190490D02*
X13772Y191448D01*
X10672Y192406D01*
G01X14805Y193398D02*
Y195698D01*
G01X13772Y196690D02*
X10672Y197648D01*
X13772Y198606D01*
G01X12687Y198261D02*
Y197035D01*
G01X10672Y199905D02*
X12894D01*
X13359Y200058D01*
X13669Y200365D01*
X13772Y200748D01*
X13669Y201131D01*
X13359Y201438D01*
X12894Y201591D01*
X10672D01*
G01X13772Y203043D02*
X10672Y204653D01*
G01Y203043D02*
X13772Y204653D01*
G01X15008Y185836D02*
Y192036D01*
X18208D01*
Y185836D01*
X15008D01*
G01X18000Y208000D02*
Y214000D01*
X30000D01*
Y208000D01*
X18000D01*
G01Y215000D02*
Y221000D01*
X30000D01*
Y215000D01*
X18000D01*
G01X16400Y228500D02*
Y234700D01*
X19600D01*
Y228500D01*
X16400D01*
G01X21155Y269335D02*
X15066D01*
G01Y269305D02*
Y298075D01*
X21155D01*
G01X16625Y261377D02*
X22825D01*
Y258177D01*
X16625D01*
Y261377D01*
G01X14737Y314359D02*
X21337D01*
Y301359D01*
X14737D01*
Y314359D01*
G01X21337Y307859D02*
X14737D01*
G01X18600Y321600D02*
Y315400D01*
X15400D01*
Y321600D01*
X18600D01*
G01X21500Y327000D02*
X15300D01*
Y330200D01*
X21500D01*
Y327000D01*
G01X17150Y343927D02*
X10850D01*
Y345493D01*
X11165Y346120D01*
X11585Y346590D01*
X12215Y346982D01*
X12950Y347295D01*
X14000Y347373D01*
X15050Y347295D01*
X15785Y346982D01*
X16415Y346590D01*
X16835Y346120D01*
X17150Y345493D01*
Y343927D01*
G01Y353517D02*
Y350383D01*
X10850D01*
Y353517D01*
G01X13895Y352263D02*
Y350383D01*
G01X13790Y358877D02*
X13475Y359190D01*
X12950Y359425D01*
X12215Y359582D01*
X11585Y359425D01*
X11165Y359112D01*
X10850Y358563D01*
Y356448D01*
X17150D01*
Y359033D01*
X16730Y359582D01*
X16100Y359895D01*
X15365Y360052D01*
X14630Y359895D01*
X14000Y359425D01*
X13790Y358877D01*
Y356448D01*
G01X10850Y362827D02*
X15365D01*
X16310Y363140D01*
X16940Y363767D01*
X17150Y364550D01*
X16940Y365333D01*
X16310Y365960D01*
X15365Y366273D01*
X10850D01*
G01X14000Y371320D02*
Y372887D01*
X15890D01*
X16520Y372417D01*
X16940Y371868D01*
X17150Y371085D01*
X16940Y370302D01*
X16520Y369753D01*
X15890Y369283D01*
X15155Y368970D01*
X14315Y368813D01*
X13580D01*
X12950Y368970D01*
X12215Y369283D01*
X11585Y369753D01*
X11165Y370223D01*
X10850Y370850D01*
Y371398D01*
X11060Y372025D01*
X11480Y372495D01*
G01X15890Y381883D02*
X16520Y382275D01*
X16940Y382745D01*
X17150Y383293D01*
X16940Y383920D01*
X16520Y384390D01*
X15890Y384860D01*
X15050Y385017D01*
X10850D01*
G01Y389750D02*
X17150D01*
G01X10850Y387948D02*
Y391552D01*
G01X17150Y394092D02*
X10850Y396050D01*
X17150Y398008D01*
G01X14945Y397303D02*
Y394797D01*
G01X14000Y402820D02*
Y404387D01*
X15890D01*
X16520Y403917D01*
X16940Y403368D01*
X17150Y402585D01*
X16940Y401802D01*
X16520Y401253D01*
X15890Y400783D01*
X15155Y400470D01*
X14315Y400313D01*
X13580D01*
X12950Y400470D01*
X12215Y400783D01*
X11585Y401253D01*
X11165Y401723D01*
X10850Y402350D01*
Y402898D01*
X11060Y403525D01*
X11480Y403995D01*
G01X16919Y337654D02*
X17187Y337706D01*
X17494Y337861D01*
X17686Y338119D01*
X17762Y338481D01*
X17686Y338842D01*
X17456Y339152D01*
X17111Y339307D01*
X16727D01*
X16497Y339411D01*
X16306Y339669D01*
X16229Y340031D01*
X16344Y340392D01*
X16612Y340651D01*
X16919Y340754D01*
X17226Y340651D01*
X17494Y340392D01*
X17609Y340031D01*
X17532Y339669D01*
X17341Y339411D01*
X17111Y339307D01*
X16727D01*
X16382Y339152D01*
X16152Y338842D01*
X16076Y338481D01*
X16152Y338119D01*
X16344Y337861D01*
X16651Y337706D01*
X16919Y337654D01*
G01X5683Y408570D02*
X5875Y408260D01*
X6105Y408053D01*
X6373Y407950D01*
X6680Y408053D01*
X6910Y408260D01*
X7140Y408570D01*
X7217Y408983D01*
Y411050D01*
G01X9473Y407950D02*
X9550Y408622D01*
X9665Y409190D01*
X9818Y409707D01*
X10010Y410275D01*
X10317Y411050D01*
X8783D01*
G01X11573Y422400D02*
X13813D01*
G01X12600Y424025D02*
Y420775D01*
G01X15700Y426700D02*
X36100D01*
Y418500D01*
X15700D01*
Y426700D01*
G01X6557Y427450D02*
Y430550D01*
X7323D01*
X7630Y430395D01*
X7860Y430188D01*
X8052Y429878D01*
X8205Y429517D01*
X8243Y429000D01*
X8205Y428483D01*
X8052Y428122D01*
X7860Y427812D01*
X7630Y427605D01*
X7323Y427450D01*
X6557D01*
G01X9772Y430033D02*
X10002Y430343D01*
X10270Y430498D01*
X10577Y430550D01*
X10960Y430447D01*
X11228Y430188D01*
X11305Y429878D01*
X11267Y429568D01*
X11113Y429310D01*
X10347Y428793D01*
X10002Y428432D01*
X9772Y427915D01*
X9695Y427450D01*
X11305D01*
G01X13600Y430550D02*
X13293Y430447D01*
X13063Y430188D01*
X12910Y429878D01*
X12795Y429465D01*
X12757Y429000D01*
X12795Y428535D01*
X12910Y428122D01*
X13063Y427812D01*
X13293Y427553D01*
X13600Y427450D01*
X13907Y427553D01*
X14137Y427812D01*
X14290Y428122D01*
X14405Y428535D01*
X14443Y429000D01*
X14405Y429465D01*
X14290Y429878D01*
X14137Y430188D01*
X13907Y430447D01*
X13600Y430550D01*
G01X27844Y30914D02*
X28151Y30656D01*
X28496Y30501D01*
X28802D01*
X29109Y30656D01*
X29339Y30914D01*
X29454Y31276D01*
X29377Y31638D01*
X29186Y31948D01*
X28841Y32154D01*
X28381Y32258D01*
X28112Y32464D01*
X27997Y32826D01*
X28074Y33188D01*
X28266Y33446D01*
X28534Y33601D01*
X28802D01*
X29071Y33498D01*
X29301Y33239D01*
G01X30599Y33601D02*
X31136Y30501D01*
X31749Y33601D01*
X32362Y30501D01*
X32899Y33601D01*
G01X34121Y31793D02*
X34389Y32154D01*
X34619Y32361D01*
X34926Y32464D01*
X35194Y32361D01*
X35386Y32154D01*
X35539Y31844D01*
X35577Y31483D01*
X35539Y31173D01*
X35386Y30863D01*
X35156Y30604D01*
X34887Y30501D01*
X34581Y30604D01*
X34312Y30914D01*
X34159Y31379D01*
X34121Y31896D01*
X34197Y32568D01*
X34312Y32929D01*
X34504Y33291D01*
X34772Y33549D01*
X35041Y33601D01*
X35309Y33498D01*
X35501Y33239D01*
G01X36896Y29488D02*
X26096D01*
G01X29906Y59117D02*
G03X36750Y68200I-2606J9084D01*
G01D02*
G03X30614Y77050I-9450J0D01*
G01X39800Y118843D02*
X33200D01*
Y131843D01*
X39800D01*
Y118843D01*
G01X31300D02*
X24700D01*
Y131843D01*
X31300D01*
Y118843D01*
G01X32872Y111570D02*
X33064Y111260D01*
X33294Y111053D01*
X33562Y110950D01*
X33869Y111053D01*
X34099Y111260D01*
X34329Y111570D01*
X34406Y111983D01*
Y114050D01*
G01X36011Y112242D02*
X36279Y112603D01*
X36509Y112810D01*
X36816Y112913D01*
X37084Y112810D01*
X37276Y112603D01*
X37429Y112293D01*
X37467Y111932D01*
X37429Y111622D01*
X37276Y111312D01*
X37046Y111053D01*
X36777Y110950D01*
X36471Y111053D01*
X36202Y111363D01*
X36049Y111828D01*
X36011Y112345D01*
X36087Y113017D01*
X36202Y113378D01*
X36394Y113740D01*
X36662Y113998D01*
X36931Y114050D01*
X37199Y113947D01*
X37391Y113688D01*
G01X33200Y125343D02*
X39800D01*
G01X24700D02*
X31300D01*
G01X28330Y185847D02*
X34530D01*
Y182647D01*
X28330D01*
Y185847D01*
G01X21692Y188971D02*
Y188700D01*
X25494D01*
G01X30094D02*
X33896D01*
Y188971D01*
G01X27794Y204842D02*
X21692D01*
Y204371D01*
G01X33896Y204842D02*
X30094D01*
G01X33015Y228258D02*
Y223658D01*
G01X43015Y223758D02*
Y223658D01*
X33015D01*
G01X26500Y223700D02*
Y228300D01*
G01X22000Y223700D02*
Y228300D01*
G01X32000Y223700D02*
Y228300D01*
G01Y223700D02*
X22000D01*
G01X27500D02*
Y228300D01*
G01X38400Y213100D02*
X32200D01*
Y216300D01*
X38400D01*
Y213100D01*
G01X33015Y228258D02*
X43015D01*
G01X22000Y228200D02*
Y228300D01*
X32000D01*
G01X22500Y237500D02*
Y243500D01*
X34500D01*
Y237500D01*
X22500D01*
G01Y230500D02*
Y236500D01*
X34500D01*
Y230500D01*
X22500D01*
G01X21805Y257237D02*
Y251037D01*
X18605D01*
Y257237D01*
X21805D01*
G01X31765Y244513D02*
X25565D01*
Y247713D01*
X31765D01*
Y244513D01*
G01X25768Y250933D02*
X24603D01*
Y253083D01*
G01X39400Y262900D02*
X33200D01*
Y266100D01*
X39400D01*
Y262900D01*
G01X32400D02*
X26200D01*
Y266100D01*
X32400D01*
Y262900D01*
G01X24603Y257051D02*
Y259201D01*
G01D02*
X25768D01*
G01X31539Y314311D02*
X38139D01*
Y301311D01*
X31539D01*
Y314311D01*
G01X23138Y314335D02*
X29738D01*
Y301335D01*
X23138D01*
Y314335D01*
G01X38139Y307811D02*
X31539D01*
G01X29738Y307835D02*
X23138D01*
G01X22600Y321600D02*
Y315400D01*
X19400D01*
Y321600D01*
X22600D01*
G01X29800Y315300D02*
X23600D01*
Y318500D01*
X29800D01*
Y315300D01*
G01X32000Y327000D02*
X29669Y329331D01*
X26560D01*
Y320669D01*
X37440D01*
Y329331D01*
X34331D01*
X32000Y327000D01*
G01X18898Y414351D02*
X28740D01*
Y333957D01*
X18898D01*
Y414351D01*
G01X33000Y413500D02*
X39200D01*
Y410300D01*
X33000D01*
Y413500D01*
G01Y417300D02*
X39200D01*
Y414100D01*
X33000D01*
Y417300D01*
G01X23400Y424600D02*
Y420500D01*
X26100Y422700D01*
X23500Y424500D01*
G01X26400Y424600D02*
Y420500D01*
G01X46063Y15065D02*
Y15465D01*
G01Y21465D02*
Y29488D01*
X43896D01*
G01X42400Y39600D02*
X48600D01*
Y36400D01*
X42400D01*
Y39600D01*
G01X41600Y36400D02*
X35400D01*
Y39600D01*
X41600D01*
Y36400D01*
G01X37400Y47307D02*
X39622D01*
X40087Y47460D01*
X40397Y47767D01*
X40500Y48150D01*
X40397Y48533D01*
X40087Y48840D01*
X39622Y48993D01*
X37400D01*
G01X39880Y50407D02*
X40242Y50637D01*
X40448Y50943D01*
X40500Y51288D01*
X40448Y51595D01*
X40190Y51902D01*
X39880Y52093D01*
X39570Y52132D01*
X39208Y52055D01*
X38950Y51787D01*
X38847Y51518D01*
Y51173D01*
G01Y51518D02*
X38692Y51748D01*
X38433Y51940D01*
X38123Y52017D01*
X37813Y51940D01*
X37555Y51748D01*
X37400Y51403D01*
X37452Y51058D01*
X37658Y50713D01*
G01X40500Y54350D02*
X37400D01*
X38020Y53890D01*
G01X40500D02*
Y54810D01*
G01X41148Y43497D02*
Y55297D01*
X49810D01*
Y43497D01*
X41148D01*
G01X40486Y59917D02*
X46686D01*
Y56717D01*
X40486D01*
Y59917D01*
G01X39593Y72463D02*
X39541Y72156D01*
X39335Y71888D01*
X39025Y71658D01*
X38663Y71505D01*
X38250Y71428D01*
X37836D01*
X37423Y71505D01*
X37061Y71658D01*
X36751Y71888D01*
X36545Y72156D01*
X36493Y72463D01*
X36545Y72770D01*
X36751Y73038D01*
X37061Y73268D01*
X37423Y73421D01*
X37836Y73498D01*
X38250D01*
X38663Y73421D01*
X39025Y73268D01*
X39335Y73038D01*
X39541Y72770D01*
X39593Y72463D01*
G01X38766Y72770D02*
X39593Y73230D01*
G01Y75563D02*
X36493D01*
X37113Y75103D01*
G01X39593D02*
Y76023D01*
G01X37010Y77935D02*
X36700Y78165D01*
X36545Y78433D01*
X36493Y78740D01*
X36596Y79123D01*
X36855Y79391D01*
X37165Y79468D01*
X37475Y79430D01*
X37733Y79276D01*
X38250Y78510D01*
X38611Y78165D01*
X39128Y77935D01*
X39593Y77858D01*
Y79468D01*
G01X48831Y73747D02*
Y70400D01*
X46631Y68500D01*
X48831Y66600D01*
Y63253D01*
X40169D01*
Y73747D01*
X48831D01*
G01X45768Y106450D02*
Y91550D01*
G01Y86450D02*
Y83803D01*
X55610D01*
Y96450D01*
G01X48300Y118843D02*
X41700D01*
Y131843D01*
X48300D01*
Y118843D01*
G01X55610Y101550D02*
Y114197D01*
X45768D01*
Y111550D01*
G01X42456Y135265D02*
X55532D01*
Y179265D01*
G01X41700Y125343D02*
X48300D01*
G01X55532Y179265D02*
X42556D01*
G01X43992Y200387D02*
Y194187D01*
X40792D01*
Y200387D01*
X43992D01*
G01X47992D02*
Y194187D01*
X44792D01*
Y200387D01*
X47992D01*
G01X42619Y189125D02*
X48819D01*
Y185925D01*
X42619D01*
Y189125D01*
G01X40786Y193135D02*
X46986D01*
Y189935D01*
X40786D01*
Y193135D01*
G01X35649Y185911D02*
X41849D01*
Y182711D01*
X35649D01*
Y185911D01*
G01X40681Y201658D02*
Y207858D01*
X43881D01*
Y201658D01*
X40681D01*
G01X40884Y212301D02*
X47084D01*
Y209101D01*
X40884D01*
Y212301D01*
G01X44707Y201658D02*
Y207858D01*
X47907D01*
Y201658D01*
X44707D01*
G01X33896Y204571D02*
Y204842D01*
G01X38515Y228258D02*
Y223658D01*
G01X43015Y228258D02*
Y223658D01*
G01X37515Y228258D02*
Y223658D01*
G01X47084Y213118D02*
X40884D01*
Y216318D01*
X47084D01*
Y213118D01*
G01X45299Y223576D02*
Y228800D01*
X47500Y230800D01*
X45299Y232800D01*
Y238024D01*
X57701D01*
Y223576D01*
X45299D01*
G01X38900Y229400D02*
Y235600D01*
X42100D01*
Y229400D01*
X38900D01*
G01X48200Y239400D02*
X42000D01*
Y242600D01*
X48200D01*
Y239400D01*
G01X45975Y257210D02*
Y251010D01*
X42775D01*
Y257210D01*
X45975D01*
G01X49000Y247200D02*
X42800D01*
Y250400D01*
X49000D01*
Y247200D01*
G01X41092Y244516D02*
X34892D01*
Y247716D01*
X41092D01*
Y244516D01*
G01X48200Y243300D02*
X42000D01*
Y246500D01*
X48200D01*
Y243300D01*
G01X46840Y251010D02*
Y257210D01*
X50040D01*
Y251010D01*
X46840D01*
G01X36807Y253083D02*
Y250933D01*
X35642D01*
G01X35355Y298075D02*
X41444D01*
Y269335D01*
X35455D01*
G01X47200Y266200D02*
X53400D01*
Y263000D01*
X47200D01*
Y266200D01*
G01X53400Y259200D02*
X47200D01*
Y262400D01*
X53400D01*
Y259200D01*
G01X39804Y261238D02*
X46004D01*
Y258038D01*
X39804D01*
Y261238D01*
G01X46070Y268500D02*
Y262300D01*
X42870D01*
Y268500D01*
X46070D01*
G01X45700Y270083D02*
X42600D01*
Y271003D01*
X42755Y271310D01*
X43117Y271540D01*
X43530Y271617D01*
X43943Y271540D01*
X44253Y271348D01*
X44408Y271003D01*
Y270083D01*
G01X42600Y273107D02*
X44822D01*
X45287Y273260D01*
X45597Y273567D01*
X45700Y273950D01*
X45597Y274333D01*
X45287Y274640D01*
X44822Y274793D01*
X42600D01*
G01X45700Y277050D02*
X42600D01*
X43220Y276590D01*
G01X45700D02*
Y277510D01*
G01X35642Y259201D02*
X36807D01*
Y257051D01*
G01X46130Y280533D02*
X43030D01*
Y281453D01*
X43185Y281760D01*
X43547Y281990D01*
X43960Y282067D01*
X44373Y281990D01*
X44683Y281798D01*
X44838Y281453D01*
Y280533D01*
G01X43030Y283633D02*
X46130D01*
Y285167D01*
G01X45510Y286657D02*
X45872Y286887D01*
X46078Y287193D01*
X46130Y287538D01*
X46078Y287845D01*
X45820Y288152D01*
X45510Y288343D01*
X45200Y288382D01*
X44838Y288305D01*
X44580Y288037D01*
X44477Y287768D01*
Y287423D01*
G01Y287768D02*
X44322Y287998D01*
X44063Y288190D01*
X43753Y288267D01*
X43443Y288190D01*
X43185Y287998D01*
X43030Y287653D01*
X43082Y287308D01*
X43288Y286963D01*
G01X45665Y289757D02*
X45923Y289987D01*
X46078Y290255D01*
X46130Y290600D01*
X46027Y290945D01*
X45820Y291213D01*
X45458Y291405D01*
X45045Y291443D01*
X44632Y291367D01*
X44373Y291175D01*
X44167Y290907D01*
X44115Y290638D01*
X44167Y290370D01*
X44373Y290025D01*
X43030Y290140D01*
Y291175D01*
G01X46540Y308017D02*
X39940D01*
G01Y314517D02*
X46540D01*
Y301517D01*
X39940D01*
Y314517D01*
G01X35300Y318700D02*
X41500D01*
Y315500D01*
X35300D01*
Y318700D01*
G01X51600Y326400D02*
X45400D01*
Y329600D01*
X51600D01*
Y326400D01*
G01X45400Y333600D02*
X51600D01*
Y330400D01*
X45400D01*
Y333600D01*
G01X51600Y322400D02*
X45400D01*
Y325600D01*
X51600D01*
Y322400D01*
G01X45116Y329083D02*
X45800D01*
G01X123856D02*
Y407823D01*
X45116D01*
Y329083D01*
G01X39950Y324107D02*
X42172D01*
X42637Y324260D01*
X42947Y324567D01*
X43050Y324950D01*
X42947Y325333D01*
X42637Y325640D01*
X42172Y325793D01*
X39950D01*
G01X41758Y327322D02*
X41397Y327590D01*
X41190Y327820D01*
X41087Y328127D01*
X41190Y328395D01*
X41397Y328587D01*
X41707Y328740D01*
X42068Y328778D01*
X42378Y328740D01*
X42688Y328587D01*
X42947Y328357D01*
X43050Y328088D01*
X42947Y327782D01*
X42637Y327513D01*
X42172Y327360D01*
X41655Y327322D01*
X40983Y327398D01*
X40622Y327513D01*
X40260Y327705D01*
X40002Y327973D01*
X39950Y328242D01*
X40053Y328510D01*
X40312Y328702D01*
G01X33400Y339600D02*
X39600D01*
Y336400D01*
X33400D01*
Y339600D01*
G01X51600Y342400D02*
X45400D01*
Y345600D01*
X51600D01*
Y342400D01*
G01X45400Y337600D02*
X51600D01*
Y334400D01*
X45400D01*
Y337600D01*
G01Y341600D02*
X51600D01*
Y338400D01*
X45400D01*
Y341600D01*
G01X36400Y350100D02*
X42600D01*
Y346900D01*
X36400D01*
Y350100D01*
G01X42100Y361600D02*
Y355400D01*
X38900D01*
Y361600D01*
X42100D01*
G01X49100Y356600D02*
Y350400D01*
X45900D01*
Y356600D01*
X49100D01*
G01X51600Y346400D02*
X45400D01*
Y349600D01*
X51600D01*
Y346400D01*
G01X36400Y353600D02*
X42600D01*
Y350400D01*
X36400D01*
Y353600D01*
G01X51600Y358400D02*
X45400D01*
Y361600D01*
X51600D01*
Y358400D01*
G01X38900Y369400D02*
Y375600D01*
X42100D01*
Y369400D01*
X38900D01*
G01X51600Y362400D02*
X45400D01*
Y365600D01*
X51600D01*
Y362400D01*
G01X38900D02*
Y368600D01*
X42100D01*
Y362400D01*
X38900D01*
G01X51600Y366400D02*
X45400D01*
Y369600D01*
X51600D01*
Y366400D01*
G01Y370400D02*
X45400D01*
Y373600D01*
X51600D01*
Y370400D01*
G01Y374400D02*
X45400D01*
Y377600D01*
X51600D01*
Y374400D01*
G01X42100Y390100D02*
Y383900D01*
X38900D01*
Y390100D01*
X42100D01*
G01X51600Y378400D02*
X45400D01*
Y381600D01*
X51600D01*
Y378400D01*
G01Y382400D02*
X45400D01*
Y385600D01*
X51600D01*
Y382400D01*
G01X45400Y389300D02*
X51600D01*
Y386100D01*
X45400D01*
Y389300D01*
G01X38900Y376400D02*
Y382600D01*
X42100D01*
Y376400D01*
X38900D01*
G01X42100Y397100D02*
Y390900D01*
X38900D01*
Y397100D01*
X42100D01*
G01X38900Y397900D02*
Y404100D01*
X42100D01*
Y397900D01*
X38900D01*
G01X45800Y399450D02*
X52000D01*
Y396250D01*
X45800D01*
Y399450D01*
G01Y402950D02*
X52000D01*
Y399750D01*
X45800D01*
Y402950D01*
G01X52000Y392750D02*
X45800D01*
Y395950D01*
X52000D01*
Y392750D01*
G01X47682Y408800D02*
Y411900D01*
X49138D01*
G01X48602Y410402D02*
X47682D01*
G01X50743Y408800D02*
Y411900D01*
X51663D01*
X51970Y411745D01*
X52200Y411383D01*
X52277Y410970D01*
X52200Y410557D01*
X52008Y410247D01*
X51663Y410092D01*
X50743D01*
G01X54840Y410350D02*
X55607D01*
Y409420D01*
X55377Y409110D01*
X55108Y408903D01*
X54725Y408800D01*
X54342Y408903D01*
X54073Y409110D01*
X53843Y409420D01*
X53690Y409782D01*
X53613Y410195D01*
Y410557D01*
X53690Y410867D01*
X53843Y411228D01*
X54073Y411538D01*
X54303Y411745D01*
X54610Y411900D01*
X54878D01*
X55185Y411797D01*
X55415Y411590D01*
G01X56752Y408800D02*
X57710Y411900D01*
X58668Y408800D01*
G01X58323Y409885D02*
X57097D01*
G01X39900Y417300D02*
X46100D01*
Y414100D01*
X39900D01*
Y417300D01*
G01Y421300D02*
X46100D01*
Y418100D01*
X39900D01*
Y421300D01*
G01X36787Y422750D02*
X39213D01*
G01X35600Y426700D02*
Y418500D01*
G01X35100Y426700D02*
Y418500D01*
G01X42400Y428100D02*
Y421900D01*
X39200D01*
Y428100D01*
X42400D01*
G01X47000Y427400D02*
Y433600D01*
X50200D01*
Y427400D01*
X47000D01*
G01X43100D02*
Y433600D01*
X46300D01*
Y427400D01*
X43100D01*
G01X59646Y32638D02*
X78150D01*
Y9016D01*
X74804D01*
Y4292D01*
G02X68898Y-1614I-5906J0D01*
G02X62992Y4292I0J5906D01*
G01Y9016D01*
X59646D01*
Y32638D01*
G01X58034Y11933D02*
X54934D01*
Y12853D01*
X55089Y13160D01*
X55451Y13390D01*
X55864Y13467D01*
X56277Y13390D01*
X56587Y13198D01*
X56742Y12853D01*
Y11933D01*
G01X54934Y14650D02*
X58034Y15187D01*
X54934Y15800D01*
X58034Y16413D01*
X54934Y16950D01*
G01X58034Y18133D02*
X54934D01*
Y19092D01*
X55089Y19398D01*
X55296Y19590D01*
X55709Y19667D01*
X56122Y19590D01*
X56381Y19360D01*
X56536Y19092D01*
Y18133D01*
G01Y19092D02*
X58034Y19667D01*
G01X59067Y20850D02*
Y23150D01*
G01X54934Y24333D02*
X58034D01*
Y25867D01*
G01Y28967D02*
Y27433D01*
X54934D01*
Y28967D01*
G01X56432Y28353D02*
Y27433D01*
G01X58034Y30457D02*
X54934D01*
Y31223D01*
X55089Y31530D01*
X55296Y31760D01*
X55606Y31952D01*
X55967Y32105D01*
X56484Y32143D01*
X57001Y32105D01*
X57362Y31952D01*
X57672Y31760D01*
X57879Y31530D01*
X58034Y31223D01*
Y30457D01*
G01X49116Y36473D02*
X55316D01*
Y33273D01*
X49116D01*
Y36473D01*
G01X55316Y36900D02*
X49116D01*
Y40100D01*
X55316D01*
Y36900D01*
G01X53380Y44883D02*
X53690Y45075D01*
X53897Y45305D01*
X54000Y45573D01*
X53897Y45880D01*
X53690Y46110D01*
X53380Y46340D01*
X52967Y46417D01*
X50900D01*
G01X54000Y48750D02*
X50900D01*
X51520Y48290D01*
G01X54000D02*
Y49210D01*
G01Y52310D02*
X50900D01*
X53122Y50892D01*
Y52808D01*
G01X101457Y57244D02*
Y37244D01*
X59961D01*
Y57244D01*
X101457D01*
G01X50900Y61400D02*
Y67600D01*
X54100D01*
Y61400D01*
X50900D01*
G01X55972Y53783D02*
X56202Y54093D01*
X56470Y54248D01*
X56777Y54300D01*
X57160Y54197D01*
X57428Y53938D01*
X57505Y53628D01*
X57467Y53318D01*
X57313Y53060D01*
X56547Y52543D01*
X56202Y52182D01*
X55972Y51665D01*
X55895Y51200D01*
X57505D01*
G01X50445Y78813D02*
X50752Y78555D01*
X51097Y78400D01*
X51403D01*
X51710Y78555D01*
X51940Y78813D01*
X52055Y79175D01*
X51978Y79537D01*
X51787Y79847D01*
X51442Y80053D01*
X50982Y80157D01*
X50713Y80363D01*
X50598Y80725D01*
X50675Y81087D01*
X50867Y81345D01*
X51135Y81500D01*
X51403D01*
X51672Y81397D01*
X51902Y81138D01*
G01X55117Y78400D02*
X53583D01*
Y81500D01*
X55117D01*
G01X54503Y80002D02*
X53583D01*
G01X56568Y78400D02*
Y81500D01*
X58332Y78400D01*
Y81500D01*
G01X59745Y78813D02*
X60052Y78555D01*
X60397Y78400D01*
X60703D01*
X61010Y78555D01*
X61240Y78813D01*
X61355Y79175D01*
X61278Y79537D01*
X61087Y79847D01*
X60742Y80053D01*
X60282Y80157D01*
X60013Y80363D01*
X59898Y80725D01*
X59975Y81087D01*
X60167Y81345D01*
X60435Y81500D01*
X60703D01*
X60972Y81397D01*
X61202Y81138D01*
G01X63650Y78400D02*
X63343Y78452D01*
X63075Y78658D01*
X62845Y78968D01*
X62692Y79330D01*
X62615Y79743D01*
Y80157D01*
X62692Y80570D01*
X62845Y80932D01*
X63075Y81242D01*
X63343Y81448D01*
X63650Y81500D01*
X63957Y81448D01*
X64225Y81242D01*
X64455Y80932D01*
X64608Y80570D01*
X64685Y80157D01*
Y79743D01*
X64608Y79330D01*
X64455Y78968D01*
X64225Y78658D01*
X63957Y78452D01*
X63650Y78400D01*
G01X65983D02*
Y81500D01*
X66942D01*
X67248Y81345D01*
X67440Y81138D01*
X67517Y80725D01*
X67440Y80312D01*
X67210Y80053D01*
X66942Y79898D01*
X65983D01*
G01X66942D02*
X67517Y78400D01*
G01X73257Y80053D02*
X73410Y80208D01*
X73525Y80467D01*
X73602Y80828D01*
X73525Y81138D01*
X73372Y81345D01*
X73103Y81500D01*
X72068D01*
Y78400D01*
X73333D01*
X73602Y78607D01*
X73755Y78917D01*
X73832Y79278D01*
X73755Y79640D01*
X73525Y79950D01*
X73257Y80053D01*
X72068D01*
G01X76050Y78400D02*
X75743Y78452D01*
X75475Y78658D01*
X75245Y78968D01*
X75092Y79330D01*
X75015Y79743D01*
Y80157D01*
X75092Y80570D01*
X75245Y80932D01*
X75475Y81242D01*
X75743Y81448D01*
X76050Y81500D01*
X76357Y81448D01*
X76625Y81242D01*
X76855Y80932D01*
X77008Y80570D01*
X77085Y80157D01*
Y79743D01*
X77008Y79330D01*
X76855Y78968D01*
X76625Y78658D01*
X76357Y78452D01*
X76050Y78400D01*
G01X78192D02*
X79150Y81500D01*
X80108Y78400D01*
G01X79763Y79485D02*
X78537D01*
G01X81483Y78400D02*
Y81500D01*
X82442D01*
X82748Y81345D01*
X82940Y81138D01*
X83017Y80725D01*
X82940Y80312D01*
X82710Y80053D01*
X82442Y79898D01*
X81483D01*
G01X82442D02*
X83017Y78400D01*
G01X84507D02*
Y81500D01*
X85273D01*
X85580Y81345D01*
X85810Y81138D01*
X86002Y80828D01*
X86155Y80467D01*
X86193Y79950D01*
X86155Y79433D01*
X86002Y79072D01*
X85810Y78762D01*
X85580Y78555D01*
X85273Y78400D01*
X84507D01*
G01X90783D02*
Y81500D01*
X91703D01*
X92010Y81345D01*
X92240Y80983D01*
X92317Y80570D01*
X92240Y80157D01*
X92048Y79847D01*
X91703Y79692D01*
X90783D01*
G01X94190Y81500D02*
X95110D01*
G01X94650D02*
Y78400D01*
G01X94190D02*
X95110D01*
G01X96868D02*
Y81500D01*
X98632Y78400D01*
Y81500D01*
G01X100850Y78400D02*
Y81500D01*
X100390Y80880D01*
G01Y78400D02*
X101310D01*
G01X54100Y74600D02*
Y68400D01*
X50900D01*
Y74600D01*
X54100D01*
G01X62318Y121555D02*
Y127755D01*
X65518D01*
Y121555D01*
X62318D01*
G01X68075Y114850D02*
X61875D01*
Y118050D01*
X68075D01*
Y114850D01*
G01X58490Y121560D02*
Y127760D01*
X61690D01*
Y121560D01*
X58490D01*
G01X53655Y128298D02*
Y122098D01*
X50455D01*
Y128298D01*
X53655D01*
G01X65600Y134800D02*
Y128600D01*
X62400D01*
Y134800D01*
X65600D01*
G01X52557Y134000D02*
Y131778D01*
X52710Y131313D01*
X53017Y131003D01*
X53400Y130900D01*
X53783Y131003D01*
X54090Y131313D01*
X54243Y131778D01*
Y134000D01*
G01X55657Y131365D02*
X55887Y131107D01*
X56155Y130952D01*
X56500Y130900D01*
X56845Y131003D01*
X57113Y131210D01*
X57305Y131572D01*
X57343Y131985D01*
X57267Y132398D01*
X57075Y132657D01*
X56807Y132863D01*
X56538Y132915D01*
X56270Y132863D01*
X55925Y132657D01*
X56040Y134000D01*
X57075D01*
G01X58757Y131520D02*
X58987Y131158D01*
X59293Y130952D01*
X59638Y130900D01*
X59945Y130952D01*
X60252Y131210D01*
X60443Y131520D01*
X60482Y131830D01*
X60405Y132192D01*
X60137Y132450D01*
X59868Y132553D01*
X59523D01*
G01X59868D02*
X60098Y132708D01*
X60290Y132967D01*
X60367Y133277D01*
X60290Y133587D01*
X60098Y133845D01*
X59753Y134000D01*
X59408Y133948D01*
X59063Y133742D01*
G01X57600Y138100D02*
Y151500D01*
G01D02*
X66400D01*
G01Y138100D02*
X57600D01*
G01X60400Y164807D02*
X62622D01*
X63087Y164960D01*
X63397Y165267D01*
X63500Y165650D01*
X63397Y166033D01*
X63087Y166340D01*
X62622Y166493D01*
X60400D01*
G01X63500Y169210D02*
X60400D01*
X62622Y167792D01*
Y169708D01*
G01X63500Y172310D02*
X60400D01*
X62622Y170892D01*
Y172808D01*
G01X51992Y200387D02*
Y194187D01*
X48792D01*
Y200387D01*
X51992D01*
G01X62000Y191500D02*
Y185300D01*
X58800D01*
Y191500D01*
X62000D01*
G01X55300Y194500D02*
Y207900D01*
G01X64100Y194500D02*
X55300D01*
G01X53449Y207858D02*
Y201658D01*
X50249D01*
Y207858D01*
X53449D01*
G01X56250Y209600D02*
X50050D01*
Y212800D01*
X56250D01*
Y209600D01*
G01X55300Y207900D02*
X64100D01*
G01Y200200D02*
X62500Y201200D01*
X64100Y202200D01*
G01X50300Y222200D02*
X56500D01*
Y219000D01*
X50300D01*
Y222200D01*
G01X59616Y224200D02*
Y230400D01*
X62816D01*
Y224200D01*
X59616D01*
G01X57957Y222700D02*
Y220478D01*
X58110Y220013D01*
X58417Y219703D01*
X58800Y219600D01*
X59183Y219703D01*
X59490Y220013D01*
X59643Y220478D01*
Y222700D01*
G01X62360Y219600D02*
Y222700D01*
X60942Y220478D01*
X62858D01*
G01X64272Y222183D02*
X64502Y222493D01*
X64770Y222648D01*
X65077Y222700D01*
X65460Y222597D01*
X65728Y222338D01*
X65805Y222028D01*
X65767Y221718D01*
X65613Y221460D01*
X64847Y220943D01*
X64502Y220582D01*
X64272Y220065D01*
X64195Y219600D01*
X65805D01*
G01X58900Y244300D02*
Y238500D01*
G01X67700D02*
X58900D01*
G01X50840Y251010D02*
Y257210D01*
X54040D01*
Y251010D01*
X50840D01*
G01X61700Y256200D02*
Y262400D01*
X64900D01*
Y256200D01*
X61700D01*
G01X58900Y252100D02*
Y246300D01*
G01Y252100D02*
X67700D01*
G01X58900Y246300D02*
X60400Y245300D01*
X58900Y244300D01*
G01X51800Y270383D02*
X48700D01*
Y271303D01*
X48855Y271610D01*
X49217Y271840D01*
X49630Y271917D01*
X50043Y271840D01*
X50353Y271648D01*
X50508Y271303D01*
Y270383D01*
G01X51180Y273407D02*
X51542Y273637D01*
X51748Y273943D01*
X51800Y274288D01*
X51748Y274595D01*
X51490Y274902D01*
X51180Y275093D01*
X50870Y275132D01*
X50508Y275055D01*
X50250Y274787D01*
X50147Y274518D01*
Y274173D01*
G01Y274518D02*
X49992Y274748D01*
X49733Y274940D01*
X49423Y275017D01*
X49113Y274940D01*
X48855Y274748D01*
X48700Y274403D01*
X48752Y274058D01*
X48958Y273713D01*
G01X48700Y276392D02*
X51800Y277350D01*
X48700Y278308D01*
G01X51180Y279607D02*
X51542Y279837D01*
X51748Y280143D01*
X51800Y280488D01*
X51748Y280795D01*
X51490Y281102D01*
X51180Y281293D01*
X50870Y281332D01*
X50508Y281255D01*
X50250Y280987D01*
X50147Y280718D01*
Y280373D01*
G01Y280718D02*
X49992Y280948D01*
X49733Y281140D01*
X49423Y281217D01*
X49113Y281140D01*
X48855Y280948D01*
X48700Y280603D01*
X48752Y280258D01*
X48958Y279913D01*
G01X52833Y282400D02*
Y284700D01*
G01X51800Y285692D02*
X48700Y286650D01*
X51800Y287608D01*
G01X50715Y287263D02*
Y286037D01*
G01X48700Y288907D02*
X50922D01*
X51387Y289060D01*
X51697Y289367D01*
X51800Y289750D01*
X51697Y290133D01*
X51387Y290440D01*
X50922Y290593D01*
X48700D01*
G01X51800Y292045D02*
X48700Y293655D01*
G01Y292045D02*
X51800Y293655D01*
G01X57907Y284120D02*
X58060Y284275D01*
X58175Y284534D01*
X58252Y284895D01*
X58175Y285205D01*
X58022Y285412D01*
X57753Y285567D01*
X56718D01*
Y282467D01*
X57983D01*
X58252Y282674D01*
X58405Y282984D01*
X58482Y283345D01*
X58405Y283707D01*
X58175Y284017D01*
X57907Y284120D01*
X56718D01*
G01X59895Y282880D02*
X60202Y282622D01*
X60547Y282467D01*
X60853D01*
X61160Y282622D01*
X61390Y282880D01*
X61505Y283242D01*
X61428Y283604D01*
X61237Y283914D01*
X60892Y284120D01*
X60432Y284224D01*
X60163Y284430D01*
X60048Y284792D01*
X60125Y285154D01*
X60317Y285412D01*
X60585Y285567D01*
X60853D01*
X61122Y285464D01*
X61352Y285205D01*
G01X62803Y282467D02*
Y285567D01*
X63800Y282984D01*
X64797Y285567D01*
Y282467D01*
G01X70613Y284275D02*
X70345Y284482D01*
X70115Y284534D01*
X69808Y284430D01*
X69578Y284224D01*
X69425Y283862D01*
X69387Y283500D01*
X69425Y283139D01*
X69578Y282829D01*
X69808Y282570D01*
X70115Y282467D01*
X70383Y282570D01*
X70613Y282777D01*
G01X73100Y282467D02*
X72870Y282519D01*
X72640Y282725D01*
X72487Y283087D01*
X72410Y283500D01*
X72487Y283914D01*
X72640Y284275D01*
X72870Y284482D01*
X73100Y284534D01*
X73330Y284482D01*
X73560Y284275D01*
X73713Y283914D01*
X73752Y283500D01*
X73713Y283087D01*
X73560Y282725D01*
X73330Y282519D01*
X73100Y282467D01*
G01X75548D02*
Y284534D01*
G01Y284017D02*
X75702Y284275D01*
X75932Y284482D01*
X76238Y284534D01*
X76507Y284482D01*
X76737Y284275D01*
X76852Y283914D01*
Y282467D01*
G01X78648D02*
Y284534D01*
G01Y284017D02*
X78802Y284275D01*
X79032Y284482D01*
X79338Y284534D01*
X79607Y284482D01*
X79837Y284275D01*
X79952Y283914D01*
Y282467D01*
G01X82400Y282364D02*
X82323Y282415D01*
Y282519D01*
X82400Y282570D01*
X82477Y282519D01*
Y282415D01*
X82400Y282364D01*
G01X62800Y281500D02*
Y275300D01*
X59600D01*
Y281500D01*
X62800D01*
G01X60128Y289210D02*
X60438Y289402D01*
X60645Y289632D01*
X60748Y289900D01*
X60645Y290207D01*
X60438Y290437D01*
X60128Y290667D01*
X59715Y290744D01*
X57648D01*
G01X60748Y293537D02*
X57648D01*
X59870Y292119D01*
Y294035D01*
G01X62303Y296881D02*
Y289705D01*
X68815D01*
G01X62303Y309481D02*
Y298581D01*
G01X48338Y304196D02*
Y310396D01*
X51538D01*
Y304196D01*
X48338D01*
G01X62600Y332600D02*
Y326400D01*
X59400D01*
Y332600D01*
X62600D01*
G01X54200Y326400D02*
Y332600D01*
X57400D01*
Y326400D01*
X54200D01*
G01X65114Y338831D02*
Y336331D01*
X65434Y336831D01*
G01Y338831D02*
X64794D01*
G01X63501Y338456D02*
X63341Y338664D01*
X63154Y338789D01*
X62914Y338831D01*
X62674Y338748D01*
X62487Y338581D01*
X62354Y338289D01*
X62327Y337956D01*
X62381Y337623D01*
X62514Y337414D01*
X62701Y337248D01*
X62887Y337206D01*
X63074Y337248D01*
X63314Y337414D01*
X63234Y336331D01*
X62514D01*
G01X61864Y335731D02*
Y333231D01*
X62184Y333731D01*
G01Y335731D02*
X61544D01*
G01X60171Y334689D02*
X59984Y334398D01*
X59824Y334231D01*
X59611Y334148D01*
X59424Y334231D01*
X59291Y334398D01*
X59184Y334648D01*
X59157Y334939D01*
X59184Y335189D01*
X59291Y335439D01*
X59451Y335648D01*
X59637Y335731D01*
X59851Y335648D01*
X60037Y335398D01*
X60144Y335023D01*
X60171Y334606D01*
X60117Y334064D01*
X60037Y333773D01*
X59904Y333481D01*
X59717Y333273D01*
X59531Y333231D01*
X59344Y333314D01*
X59211Y333523D01*
G01X56927Y340894D02*
X112045D01*
Y396012D01*
X56927D01*
Y340894D01*
G01X64600Y407600D02*
Y401400D01*
X61400D01*
Y407600D01*
X64600D01*
G01X60907Y413200D02*
Y410978D01*
X61060Y410513D01*
X61367Y410203D01*
X61750Y410100D01*
X62133Y410203D01*
X62440Y410513D01*
X62593Y410978D01*
Y413200D01*
G01X64850Y410100D02*
Y413200D01*
X64390Y412580D01*
G01Y410100D02*
X65310D01*
G01X67107Y410720D02*
X67337Y410358D01*
X67643Y410152D01*
X67988Y410100D01*
X68295Y410152D01*
X68602Y410410D01*
X68793Y410720D01*
X68832Y411030D01*
X68755Y411392D01*
X68487Y411650D01*
X68218Y411753D01*
X67873D01*
G01X68218D02*
X68448Y411908D01*
X68640Y412167D01*
X68717Y412477D01*
X68640Y412787D01*
X68448Y413045D01*
X68103Y413200D01*
X67758Y413148D01*
X67413Y412942D01*
G01X55563Y421214D02*
X57063Y422986D01*
X60803D01*
Y414324D01*
X50323D01*
Y422986D01*
X54063D01*
X55563Y421214D01*
G01X50900Y427400D02*
Y433600D01*
X52100D01*
G01X54100Y432100D02*
Y428800D01*
G01X52400Y427400D02*
X50900D01*
G01X56600Y433600D02*
X58100D01*
Y427400D01*
X56600D01*
G01X54900Y428700D02*
Y432000D01*
G01X52224Y434645D02*
X52800D01*
G01X56800D02*
X73000D01*
G01X65482Y437195D02*
X65329Y437040D01*
X65214Y436781D01*
X65137Y436420D01*
X65214Y436110D01*
X65367Y435903D01*
X65636Y435748D01*
X66671D01*
Y438848D01*
X65406D01*
X65137Y438641D01*
X64984Y438331D01*
X64907Y437970D01*
X64984Y437608D01*
X65214Y437298D01*
X65482Y437195D01*
X66671D01*
G01X62766Y438848D02*
X62689Y438176D01*
X62574Y437608D01*
X62421Y437091D01*
X62229Y436523D01*
X61922Y435748D01*
X63456D01*
G01X59589D02*
X59896Y435851D01*
X60126Y436110D01*
X60279Y436420D01*
X60394Y436833D01*
X60432Y437298D01*
X60394Y437763D01*
X60279Y438176D01*
X60126Y438486D01*
X59896Y438745D01*
X59589Y438848D01*
X59282Y438745D01*
X59052Y438486D01*
X58899Y438176D01*
X58784Y437763D01*
X58746Y437298D01*
X58784Y436833D01*
X58899Y436420D01*
X59052Y436110D01*
X59282Y435851D01*
X59589Y435748D01*
G01X52224Y450393D02*
Y471063D01*
X55177Y474015D01*
X121555D01*
X124508Y471063D01*
Y451870D01*
G03X129921Y446456I5413J-1D01*
G03X135335Y451870I0J5414D01*
G01Y471063D01*
X138287Y474015D01*
X171595D01*
X174547Y471063D01*
Y450098D01*
G03X178189Y446456I3642J0D01*
G03X181831Y450098I0J3642D01*
G01Y471063D01*
X184783Y474015D01*
X251122D01*
X254075Y471063D01*
Y450885D01*
G03X258504Y446456I4429J0D01*
G03X262933Y450885I0J4429D01*
G01Y471063D01*
X265886Y474015D01*
X299173D01*
X302126Y471063D01*
Y450393D01*
G01X69907Y33400D02*
Y36500D01*
X70673D01*
X70980Y36345D01*
X71210Y36138D01*
X71402Y35828D01*
X71555Y35467D01*
X71593Y34950D01*
X71555Y34433D01*
X71402Y34072D01*
X71210Y33762D01*
X70980Y33555D01*
X70673Y33400D01*
X69907D01*
G01X73850D02*
Y36500D01*
X73390Y35880D01*
G01Y33400D02*
X74310D01*
G01X77410D02*
Y36500D01*
X75992Y34278D01*
X77908D01*
G01X65709Y75000D02*
Y58100D01*
X68009Y60400D01*
G01X65709Y58100D02*
X63509Y60300D01*
G01X63985Y84008D02*
X66207D01*
X66672Y84161D01*
X66982Y84468D01*
X67085Y84851D01*
X66982Y85234D01*
X66672Y85541D01*
X66207Y85694D01*
X63985D01*
G01X67085Y86993D02*
X63985Y87951D01*
X67085Y88909D01*
G01X66000Y88564D02*
Y87338D01*
G01X67085Y90284D02*
X63985D01*
Y91243D01*
X64140Y91549D01*
X64347Y91741D01*
X64760Y91818D01*
X65173Y91741D01*
X65432Y91511D01*
X65587Y91243D01*
Y90284D01*
G01Y91243D02*
X67085Y91818D01*
G01X63985Y94151D02*
X67085D01*
G01X63985Y93269D02*
Y95033D01*
G01X67085Y99508D02*
X63985D01*
Y100274D01*
X64140Y100581D01*
X64347Y100811D01*
X64657Y101003D01*
X65018Y101156D01*
X65535Y101194D01*
X66052Y101156D01*
X66413Y101003D01*
X66723Y100811D01*
X66930Y100581D01*
X67085Y100274D01*
Y99508D01*
G01Y104218D02*
Y102684D01*
X63985D01*
Y104218D01*
G01X65483Y103604D02*
Y102684D01*
G01X65432Y106858D02*
X65277Y107011D01*
X65018Y107126D01*
X64657Y107203D01*
X64347Y107126D01*
X64140Y106973D01*
X63985Y106704D01*
Y105669D01*
X67085D01*
Y106934D01*
X66878Y107203D01*
X66568Y107356D01*
X66207Y107433D01*
X65845Y107356D01*
X65535Y107126D01*
X65432Y106858D01*
Y105669D01*
G01X63985Y108808D02*
X66207D01*
X66672Y108961D01*
X66982Y109268D01*
X67085Y109651D01*
X66982Y110034D01*
X66672Y110341D01*
X66207Y110494D01*
X63985D01*
G01X65535Y112981D02*
Y113748D01*
X66465D01*
X66775Y113518D01*
X66982Y113249D01*
X67085Y112866D01*
X66982Y112483D01*
X66775Y112214D01*
X66465Y111984D01*
X66103Y111831D01*
X65690Y111754D01*
X65328D01*
X65018Y111831D01*
X64657Y111984D01*
X64347Y112214D01*
X64140Y112444D01*
X63985Y112751D01*
Y113019D01*
X64088Y113326D01*
X64295Y113556D01*
G01X76241Y84493D02*
X70152D01*
Y113233D01*
X76141D01*
G01X82666Y116616D02*
X76466D01*
Y119816D01*
X82666D01*
Y116616D01*
G01X73063Y131348D02*
X69961D01*
G01Y123214D02*
Y123080D01*
X73063D01*
G01X76963Y131348D02*
X75163D01*
G01X69961D02*
Y131214D01*
G01X79119Y134266D02*
X72919D01*
Y137466D01*
X79119D01*
Y134266D01*
G01X76150Y144903D02*
Y138303D01*
G01X69650D02*
Y144903D01*
X82650D01*
Y138303D01*
X69650D01*
G01X76150Y152388D02*
Y145788D01*
G01X69650D02*
Y152388D01*
X82650D01*
Y145788D01*
X69650D01*
G01X66400Y145800D02*
Y151500D01*
G01Y138100D02*
Y143800D01*
G01D02*
X64800Y144800D01*
X66400Y145800D01*
G01X77100Y159600D02*
Y153400D01*
X73900D01*
Y159600D01*
X77100D01*
G01X66349Y168210D02*
X64578Y169710D01*
Y174841D01*
X73042D01*
Y161579D01*
X64578D01*
Y166710D01*
X66349Y168210D01*
G01X74400Y185400D02*
Y179200D01*
X71200D01*
Y185400D01*
X74400D01*
G01X67600Y179200D02*
Y185400D01*
X70800D01*
Y179200D01*
X67600D01*
G01X63900D02*
Y185400D01*
X67100D01*
Y179200D01*
X63900D01*
G01X65200Y193857D02*
X67422D01*
X67887Y194010D01*
X68197Y194317D01*
X68300Y194700D01*
X68197Y195083D01*
X67887Y195390D01*
X67422Y195543D01*
X65200D01*
G01X68300Y197800D02*
X65200D01*
X65820Y197340D01*
G01X68300D02*
Y198260D01*
G01Y200900D02*
X68248Y201168D01*
X68093Y201475D01*
X67835Y201667D01*
X67473Y201743D01*
X67112Y201667D01*
X66802Y201437D01*
X66647Y201092D01*
Y200708D01*
X66543Y200478D01*
X66285Y200287D01*
X65923Y200210D01*
X65562Y200325D01*
X65303Y200593D01*
X65200Y200900D01*
X65303Y201207D01*
X65562Y201475D01*
X65923Y201590D01*
X66285Y201513D01*
X66543Y201322D01*
X66647Y201092D01*
Y200708D01*
X66802Y200363D01*
X67112Y200133D01*
X67473Y200057D01*
X67835Y200133D01*
X68093Y200325D01*
X68248Y200632D01*
X68300Y200900D01*
G01X64100Y194500D02*
Y200200D01*
G01Y202200D02*
Y207900D01*
G01X71800Y218100D02*
Y224300D01*
X75000D01*
Y218100D01*
X71800D01*
G01X75900D02*
Y224300D01*
X79100D01*
Y218100D01*
X75900D01*
G01X63616Y224200D02*
Y230400D01*
X66816D01*
Y224200D01*
X63616D01*
G01X73800Y228300D02*
Y234500D01*
X77000D01*
Y228300D01*
X73800D01*
G01X68350Y238507D02*
X70572D01*
X71037Y238660D01*
X71347Y238967D01*
X71450Y239350D01*
X71347Y239733D01*
X71037Y240040D01*
X70572Y240193D01*
X68350D01*
G01X70830Y241607D02*
X71192Y241837D01*
X71398Y242143D01*
X71450Y242488D01*
X71398Y242795D01*
X71140Y243102D01*
X70830Y243293D01*
X70520Y243332D01*
X70158Y243255D01*
X69900Y242987D01*
X69797Y242718D01*
Y242373D01*
G01Y242718D02*
X69642Y242948D01*
X69383Y243140D01*
X69073Y243217D01*
X68763Y243140D01*
X68505Y242948D01*
X68350Y242603D01*
X68402Y242258D01*
X68608Y241913D01*
G01X67700Y252100D02*
Y238500D01*
G01X80534Y242000D02*
Y248800D01*
X72266D01*
Y247534D01*
X74400Y245400D01*
X72266Y243266D01*
Y242000D01*
X80534D01*
G01X68400Y245057D02*
X70622D01*
X71087Y245210D01*
X71397Y245517D01*
X71500Y245900D01*
X71397Y246283D01*
X71087Y246590D01*
X70622Y246743D01*
X68400D01*
G01X71035Y248157D02*
X71293Y248387D01*
X71448Y248655D01*
X71500Y249000D01*
X71397Y249345D01*
X71190Y249613D01*
X70828Y249805D01*
X70415Y249843D01*
X70002Y249767D01*
X69743Y249575D01*
X69537Y249307D01*
X69485Y249038D01*
X69537Y248770D01*
X69743Y248425D01*
X68400Y248540D01*
Y249575D01*
G01X71500Y252100D02*
X68400D01*
X69020Y251640D01*
G01X71500D02*
Y252560D01*
G01X72050Y279100D02*
Y268900D01*
X67450D01*
Y279100D01*
X72050D01*
G01X74900Y260800D02*
X81100D01*
Y257600D01*
X74900D01*
Y260800D01*
G01X81100Y274100D02*
Y267900D01*
X77900D01*
Y274100D01*
X81100D01*
G01X70900Y256900D02*
Y263100D01*
X74100D01*
Y256900D01*
X70900D01*
G01X72050Y274000D02*
X67450D01*
G01X66700Y281600D02*
Y275400D01*
X63500D01*
Y281600D01*
X66700D01*
G01X76100Y278600D02*
Y272400D01*
X72900D01*
Y278600D01*
X76100D01*
G01X74915Y289705D02*
X82565D01*
G01X66500Y332600D02*
Y326400D01*
X63300D01*
Y332600D01*
X66500D01*
G01X78100Y332730D02*
Y326530D01*
X74900D01*
Y332730D01*
X78100D01*
G01X70400Y332900D02*
Y326700D01*
X67200D01*
Y332900D01*
X70400D01*
G01X83565Y317855D02*
X75915D01*
G01X67848D02*
X67517D01*
G01X80762Y335731D02*
Y333231D01*
X81082Y333731D01*
G01Y335731D02*
X80442D01*
G01X78562Y333231D02*
X78775Y333314D01*
X78935Y333523D01*
X79042Y333773D01*
X79122Y334106D01*
X79149Y334481D01*
X79122Y334856D01*
X79042Y335189D01*
X78935Y335439D01*
X78775Y335648D01*
X78562Y335731D01*
X78349Y335648D01*
X78189Y335439D01*
X78082Y335189D01*
X78002Y334856D01*
X77975Y334481D01*
X78002Y334106D01*
X78082Y333773D01*
X78189Y333523D01*
X78349Y333314D01*
X78562Y333231D01*
G01X77712Y338831D02*
Y336331D01*
X78032Y336831D01*
G01Y338831D02*
X77392D01*
G01X75512D02*
Y336331D01*
X75832Y336831D01*
G01Y338831D02*
X75192D01*
G01X74462Y335731D02*
Y333231D01*
X74782Y333731D01*
G01Y335731D02*
X74142D01*
G01X72769Y333648D02*
X72609Y333398D01*
X72422Y333273D01*
X72209Y333231D01*
X71942Y333314D01*
X71755Y333523D01*
X71702Y333773D01*
X71729Y334023D01*
X71835Y334231D01*
X72369Y334648D01*
X72609Y334939D01*
X72769Y335356D01*
X72822Y335731D01*
X71702D01*
G01X71413Y338831D02*
Y336331D01*
X71733Y336831D01*
G01Y338831D02*
X71093D01*
G01X69800Y338331D02*
X69640Y338623D01*
X69426Y338789D01*
X69186Y338831D01*
X68973Y338789D01*
X68760Y338581D01*
X68626Y338331D01*
X68600Y338081D01*
X68653Y337789D01*
X68840Y337581D01*
X69026Y337498D01*
X69266D01*
G01X69026D02*
X68866Y337373D01*
X68733Y337164D01*
X68680Y336914D01*
X68733Y336664D01*
X68866Y336456D01*
X69106Y336331D01*
X69346Y336373D01*
X69586Y336539D01*
G01X68163Y335731D02*
Y333231D01*
X68483Y333731D01*
G01Y335731D02*
X67843D01*
G01X65643D02*
Y333231D01*
X66630Y335023D01*
X65296D01*
G01X76600Y407600D02*
Y401400D01*
X73400D01*
Y407600D01*
X76600D01*
G01X65400Y401400D02*
Y407600D01*
X68600D01*
Y401400D01*
X65400D01*
G01X69400D02*
Y407600D01*
X72600D01*
Y401400D01*
X69400D01*
G01X77400D02*
Y407600D01*
X80600D01*
Y401400D01*
X77400D01*
G01X67850Y422850D02*
Y416650D01*
X64650D01*
Y422850D01*
X67850D01*
G01X71073Y411158D02*
Y423639D01*
X86427D01*
Y410961D01*
X71073D01*
G01X77800Y434645D02*
X86500D01*
G01X86220Y32638D02*
X104724D01*
Y9016D01*
X101378D01*
Y4292D01*
G02X95472Y-1614I-5906J0D01*
G02X89566Y4292I0J5906D01*
G01Y9016D01*
X86220D01*
Y32638D01*
G01X84534Y11895D02*
X81434D01*
G01Y13505D02*
X84534D01*
G01X82984D02*
Y11895D01*
G01X84534Y14957D02*
X81434D01*
Y15723D01*
X81589Y16030D01*
X81796Y16260D01*
X82106Y16452D01*
X82467Y16605D01*
X82984Y16643D01*
X83501Y16605D01*
X83862Y16452D01*
X84172Y16260D01*
X84379Y16030D01*
X84534Y15723D01*
Y14957D01*
G01Y18057D02*
X81434D01*
Y18823D01*
X81589Y19130D01*
X81796Y19360D01*
X82106Y19552D01*
X82467Y19705D01*
X82984Y19743D01*
X83501Y19705D01*
X83862Y19552D01*
X84172Y19360D01*
X84379Y19130D01*
X84534Y18823D01*
Y18057D01*
G01X85567Y20850D02*
Y23150D01*
G01X81434Y24333D02*
X84534D01*
Y25867D01*
G01Y28967D02*
Y27433D01*
X81434D01*
Y28967D01*
G01X82932Y28353D02*
Y27433D01*
G01X84534Y30457D02*
X81434D01*
Y31223D01*
X81589Y31530D01*
X81796Y31760D01*
X82106Y31952D01*
X82467Y32105D01*
X82984Y32143D01*
X83501Y32105D01*
X83862Y31952D01*
X84172Y31760D01*
X84379Y31530D01*
X84534Y31223D01*
Y30457D01*
G01X86307Y33400D02*
Y36500D01*
X87073D01*
X87380Y36345D01*
X87610Y36138D01*
X87802Y35828D01*
X87955Y35467D01*
X87993Y34950D01*
X87955Y34433D01*
X87802Y34072D01*
X87610Y33762D01*
X87380Y33555D01*
X87073Y33400D01*
X86307D01*
G01X90250D02*
Y36500D01*
X89790Y35880D01*
G01Y33400D02*
X90710D01*
G01X92507Y33865D02*
X92737Y33607D01*
X93005Y33452D01*
X93350Y33400D01*
X93695Y33503D01*
X93963Y33710D01*
X94155Y34072D01*
X94193Y34485D01*
X94117Y34898D01*
X93925Y35157D01*
X93657Y35363D01*
X93388Y35415D01*
X93120Y35363D01*
X92775Y35157D01*
X92890Y36500D01*
X93925D01*
G01X96530Y113263D02*
Y84493D01*
X90441D01*
G01Y113233D02*
X96530D01*
G01X93525Y123696D02*
Y117496D01*
X90325D01*
Y123696D01*
X93525D01*
G01X86483Y120372D02*
Y126572D01*
X89683D01*
Y120372D01*
X86483D01*
G01X89300Y128283D02*
X86200D01*
Y129203D01*
X86355Y129510D01*
X86717Y129740D01*
X87130Y129817D01*
X87543Y129740D01*
X87853Y129548D01*
X88008Y129203D01*
Y128283D01*
G01X86200Y131307D02*
X88422D01*
X88887Y131460D01*
X89197Y131767D01*
X89300Y132150D01*
X89197Y132533D01*
X88887Y132840D01*
X88422Y132993D01*
X86200D01*
G01X89300Y135710D02*
X86200D01*
X88422Y134292D01*
Y136208D01*
G01X86717Y137622D02*
X86407Y137852D01*
X86252Y138120D01*
X86200Y138427D01*
X86303Y138810D01*
X86562Y139078D01*
X86872Y139155D01*
X87182Y139117D01*
X87440Y138963D01*
X87957Y138197D01*
X88318Y137852D01*
X88835Y137622D01*
X89300Y137545D01*
Y139155D01*
G01X79063Y123080D02*
X82165D01*
Y123214D01*
G01Y131214D02*
Y131348D01*
X79063D01*
G01X94005Y136581D02*
Y130381D01*
X90805D01*
Y136581D01*
X94005D01*
G01X92215Y145535D02*
X89115D01*
Y146455D01*
X89270Y146762D01*
X89632Y146992D01*
X90045Y147069D01*
X90458Y146992D01*
X90768Y146800D01*
X90923Y146455D01*
Y145535D01*
G01X92215Y149402D02*
X89115D01*
X89735Y148942D01*
G01X92215D02*
Y149862D01*
G01X89115Y151544D02*
X92215Y152502D01*
X89115Y153460D01*
G01Y155602D02*
X89218Y155295D01*
X89477Y155065D01*
X89787Y154912D01*
X90200Y154797D01*
X90665Y154759D01*
X91130Y154797D01*
X91543Y154912D01*
X91853Y155065D01*
X92112Y155295D01*
X92215Y155602D01*
X92112Y155909D01*
X91853Y156139D01*
X91543Y156292D01*
X91130Y156407D01*
X90665Y156445D01*
X90200Y156407D01*
X89787Y156292D01*
X89477Y156139D01*
X89218Y155909D01*
X89115Y155602D01*
G01X93248Y157552D02*
Y159852D01*
G01X92215Y160844D02*
X89115Y161802D01*
X92215Y162760D01*
G01X91130Y162415D02*
Y161189D01*
G01X89115Y164059D02*
X91337D01*
X91802Y164212D01*
X92112Y164519D01*
X92215Y164902D01*
X92112Y165285D01*
X91802Y165592D01*
X91337Y165745D01*
X89115D01*
G01X92215Y167197D02*
X89115Y168807D01*
G01Y167197D02*
X92215Y168807D01*
G01X78200Y159000D02*
X82800D01*
G01X78200Y163500D02*
X82800D01*
G01X78200Y153500D02*
X82800D01*
G01X82700Y163500D02*
X82800D01*
Y153500D01*
G01X78200D02*
Y163500D01*
G01Y158000D02*
X82800D01*
G01X83100Y172000D02*
Y165800D01*
X79900D01*
Y172000D01*
X83100D01*
G01X93160Y203138D02*
Y206238D01*
G01X94770D02*
Y203138D01*
G01Y204688D02*
X93160D01*
G01X96337Y205721D02*
X96567Y206031D01*
X96835Y206186D01*
X97142Y206238D01*
X97525Y206135D01*
X97793Y205876D01*
X97870Y205566D01*
X97832Y205256D01*
X97678Y204998D01*
X96912Y204481D01*
X96567Y204120D01*
X96337Y203603D01*
X96260Y203138D01*
X97870D01*
G01X79900Y218100D02*
Y224300D01*
X83100D01*
Y218100D01*
X79900D01*
G01X87557Y233600D02*
Y231378D01*
X87710Y230913D01*
X88017Y230603D01*
X88400Y230500D01*
X88783Y230603D01*
X89090Y230913D01*
X89243Y231378D01*
Y233600D01*
G01X90657Y230965D02*
X90887Y230707D01*
X91155Y230552D01*
X91500Y230500D01*
X91845Y230603D01*
X92113Y230810D01*
X92305Y231172D01*
X92343Y231585D01*
X92267Y231998D01*
X92075Y232257D01*
X91807Y232463D01*
X91538Y232515D01*
X91270Y232463D01*
X90925Y232257D01*
X91040Y233600D01*
X92075D01*
G01X94600D02*
X94293Y233497D01*
X94063Y233238D01*
X93910Y232928D01*
X93795Y232515D01*
X93757Y232050D01*
X93795Y231585D01*
X93910Y231172D01*
X94063Y230862D01*
X94293Y230603D01*
X94600Y230500D01*
X94907Y230603D01*
X95137Y230862D01*
X95290Y231172D01*
X95405Y231585D01*
X95443Y232050D01*
X95405Y232515D01*
X95290Y232928D01*
X95137Y233238D01*
X94907Y233497D01*
X94600Y233600D01*
G01X91900Y252100D02*
Y238500D01*
G01X83100Y244300D02*
Y238500D01*
G01X91900D02*
X83100D01*
G01X88400Y257100D02*
X94600D01*
Y253900D01*
X88400D01*
Y257100D01*
G01X83100Y252100D02*
Y246300D01*
G01Y252100D02*
X91900D01*
G01X83100Y246300D02*
X84600Y245300D01*
X83100Y244300D01*
G01X89900Y267900D02*
Y274100D01*
X93100D01*
Y267900D01*
X89900D01*
G01X85100Y274100D02*
Y267900D01*
X81900D01*
Y274100D01*
X85100D01*
G01X89100D02*
Y267900D01*
X85900D01*
Y274100D01*
X89100D01*
G01X91900Y257400D02*
Y263600D01*
X95100D01*
Y257400D01*
X91900D01*
G01X84900Y257200D02*
Y263400D01*
X88100D01*
Y257200D01*
X84900D01*
G01X89204Y328720D02*
Y334920D01*
X92404D01*
Y328720D01*
X89204D01*
G01X83000Y329083D02*
X87400D01*
G01X83364Y338539D02*
X83178Y338748D01*
X82964Y338831D01*
X82751Y338748D01*
X82564Y338498D01*
X82431Y338123D01*
X82378Y337748D01*
Y337289D01*
X82431Y336914D01*
X82564Y336581D01*
X82724Y336414D01*
X82911Y336331D01*
X83124Y336414D01*
X83284Y336581D01*
X83391Y336831D01*
X83444Y337164D01*
X83391Y337456D01*
X83258Y337748D01*
X83098Y337914D01*
X82911Y337956D01*
X82698Y337873D01*
X82538Y337664D01*
X82378Y337289D01*
G01X89263Y338831D02*
X89210Y338289D01*
X89130Y337831D01*
X89023Y337414D01*
X88890Y336956D01*
X88677Y336331D01*
X89743D01*
G01X86061Y334331D02*
X85874Y334289D01*
X85661Y334164D01*
X85528Y333956D01*
X85474Y333664D01*
X85528Y333373D01*
X85688Y333123D01*
X85928Y332998D01*
X86194D01*
X86354Y332914D01*
X86488Y332706D01*
X86541Y332414D01*
X86461Y332123D01*
X86274Y331914D01*
X86061Y331831D01*
X85848Y331914D01*
X85661Y332123D01*
X85581Y332414D01*
X85634Y332706D01*
X85768Y332914D01*
X85928Y332998D01*
X86194D01*
X86434Y333123D01*
X86594Y333373D01*
X86648Y333664D01*
X86594Y333956D01*
X86461Y334164D01*
X86248Y334289D01*
X86061Y334331D01*
G01X94100Y407600D02*
Y401400D01*
X90900D01*
Y407600D01*
X94100D01*
G01X90100D02*
Y401400D01*
X86900D01*
Y407600D01*
X90100D01*
G01X86100D02*
Y401400D01*
X82900D01*
Y407600D01*
X86100D01*
G01X88150Y418600D02*
X94350D01*
Y415400D01*
X88150D01*
Y418600D01*
G01Y414100D02*
X94350D01*
Y410900D01*
X88150D01*
Y414100D01*
G01X96090Y426420D02*
X89890D01*
Y429620D01*
X96090D01*
Y426420D01*
G01X79257Y428000D02*
Y425778D01*
X79410Y425313D01*
X79717Y425003D01*
X80100Y424900D01*
X80483Y425003D01*
X80790Y425313D01*
X80943Y425778D01*
Y428000D01*
G01X83200Y424900D02*
Y428000D01*
X82740Y427380D01*
G01Y424900D02*
X83660D01*
G01X85572Y427483D02*
X85802Y427793D01*
X86070Y427948D01*
X86377Y428000D01*
X86760Y427897D01*
X87028Y427638D01*
X87105Y427328D01*
X87067Y427018D01*
X86913Y426760D01*
X86147Y426243D01*
X85802Y425882D01*
X85572Y425365D01*
X85495Y424900D01*
X87105D01*
G01X90500Y434645D02*
X101500D01*
G01X107100Y15590D02*
Y16510D01*
G01Y16050D02*
X110200D01*
G01Y15590D02*
Y16510D01*
G01Y18307D02*
X107100D01*
Y19073D01*
X107255Y19380D01*
X107462Y19610D01*
X107772Y19802D01*
X108133Y19955D01*
X108650Y19993D01*
X109167Y19955D01*
X109528Y19802D01*
X109838Y19610D01*
X110045Y19380D01*
X110200Y19073D01*
Y18307D01*
G01X111233Y21100D02*
Y23400D01*
G01X107100Y24583D02*
X110200D01*
Y26117D01*
G01Y29217D02*
Y27683D01*
X107100D01*
Y29217D01*
G01X108598Y28603D02*
Y27683D01*
G01X110200Y30707D02*
X107100D01*
Y31473D01*
X107255Y31780D01*
X107462Y32010D01*
X107772Y32202D01*
X108133Y32355D01*
X108650Y32393D01*
X109167Y32355D01*
X109528Y32202D01*
X109838Y32010D01*
X110045Y31780D01*
X110200Y31473D01*
Y30707D01*
G01X100280Y33335D02*
X100357Y34007D01*
X100472Y34575D01*
X100625Y35092D01*
X100817Y35660D01*
X101124Y36435D01*
X99590D01*
G01X110100Y43600D02*
Y37400D01*
X106900D01*
Y43600D01*
X110100D01*
G01X106276Y57701D02*
X111500D01*
X113500Y55500D01*
X115500Y57701D01*
X120724D01*
Y45299D01*
X106276D01*
Y57701D01*
G01X117315Y63180D02*
Y61575D01*
X105315D01*
Y63370D01*
G01X102400Y50107D02*
X104622D01*
X105087Y50260D01*
X105397Y50567D01*
X105500Y50950D01*
X105397Y51333D01*
X105087Y51640D01*
X104622Y51793D01*
X102400D01*
G01X105138Y53398D02*
X105397Y53667D01*
X105500Y53973D01*
X105397Y54280D01*
X105087Y54548D01*
X104622Y54740D01*
X104157Y54817D01*
X103588D01*
X103123Y54740D01*
X102710Y54548D01*
X102503Y54318D01*
X102400Y54050D01*
X102503Y53743D01*
X102710Y53513D01*
X103020Y53360D01*
X103433Y53283D01*
X103795Y53360D01*
X104157Y53552D01*
X104363Y53782D01*
X104415Y54050D01*
X104312Y54357D01*
X104053Y54587D01*
X103588Y54817D01*
G01X95659Y58494D02*
X95927Y58546D01*
X96234Y58701D01*
X96426Y58959D01*
X96502Y59321D01*
X96426Y59682D01*
X96196Y59992D01*
X95851Y60147D01*
X95467D01*
X95237Y60251D01*
X95046Y60509D01*
X94969Y60871D01*
X95084Y61232D01*
X95352Y61491D01*
X95659Y61594D01*
X95966Y61491D01*
X96234Y61232D01*
X96349Y60871D01*
X96272Y60509D01*
X96081Y60251D01*
X95851Y60147D01*
X95467D01*
X95122Y59992D01*
X94892Y59682D01*
X94816Y59321D01*
X94892Y58959D01*
X95084Y58701D01*
X95391Y58546D01*
X95659Y58494D01*
G01X107150Y70467D02*
X106843Y70519D01*
X106575Y70725D01*
X106345Y71035D01*
X106192Y71397D01*
X106115Y71810D01*
Y72224D01*
X106192Y72637D01*
X106345Y72999D01*
X106575Y73309D01*
X106843Y73515D01*
X107150Y73567D01*
X107457Y73515D01*
X107725Y73309D01*
X107955Y72999D01*
X108108Y72637D01*
X108185Y72224D01*
Y71810D01*
X108108Y71397D01*
X107955Y71035D01*
X107725Y70725D01*
X107457Y70519D01*
X107150Y70467D01*
G01X107457Y71294D02*
X107917Y70467D01*
G01X109522Y73050D02*
X109752Y73360D01*
X110020Y73515D01*
X110327Y73567D01*
X110710Y73464D01*
X110978Y73205D01*
X111055Y72895D01*
X111017Y72585D01*
X110863Y72327D01*
X110097Y71810D01*
X109752Y71449D01*
X109522Y70932D01*
X109445Y70467D01*
X111055D01*
G01X105315Y66490D02*
Y68375D01*
G01D02*
X117315D01*
Y66920D01*
G01X108400Y89600D02*
Y83400D01*
X105200D01*
Y89600D01*
X108400D01*
G01X102900Y81600D02*
X109100D01*
Y78400D01*
X102900D01*
Y81600D01*
G01X101200Y83400D02*
Y89600D01*
X104400D01*
Y83400D01*
X101200D01*
G01X98400Y91400D02*
Y97600D01*
X101600D01*
Y91400D01*
X98400D01*
G01X112600Y100400D02*
X106400D01*
Y103600D01*
X112600D01*
Y100400D01*
G01Y105900D02*
X106400D01*
Y109100D01*
X112600D01*
Y105900D01*
G01X98100Y117500D02*
Y123700D01*
X101300D01*
Y117500D01*
X98100D01*
G01X94200D02*
Y123700D01*
X97400D01*
Y117500D01*
X94200D01*
G01X98800Y130400D02*
Y136600D01*
X102000D01*
Y130400D01*
X98800D01*
G01X94800D02*
Y136600D01*
X98000D01*
Y130400D01*
X94800D01*
G01X100100Y230607D02*
X102322D01*
X102787Y230760D01*
X103097Y231067D01*
X103200Y231450D01*
X103097Y231833D01*
X102787Y232140D01*
X102322Y232293D01*
X100100D01*
G01X100617Y233822D02*
X100307Y234052D01*
X100152Y234320D01*
X100100Y234627D01*
X100203Y235010D01*
X100462Y235278D01*
X100772Y235355D01*
X101082Y235317D01*
X101340Y235163D01*
X101857Y234397D01*
X102218Y234052D01*
X102735Y233822D01*
X103200Y233745D01*
Y235355D01*
G01X106307Y233100D02*
Y230878D01*
X106460Y230413D01*
X106767Y230103D01*
X107150Y230000D01*
X107533Y230103D01*
X107840Y230413D01*
X107993Y230878D01*
Y233100D01*
G01X110710Y230000D02*
Y233100D01*
X109292Y230878D01*
X111208D01*
G01X113273Y230000D02*
X113350Y230672D01*
X113465Y231240D01*
X113618Y231757D01*
X113810Y232325D01*
X114117Y233100D01*
X112583D01*
G01X103100Y262600D02*
Y256400D01*
X99900D01*
Y262600D01*
X103100D01*
G01X98900Y262400D02*
Y256200D01*
X95700D01*
Y262400D01*
X98900D01*
G01X105200Y255000D02*
Y261200D01*
X108400D01*
Y255000D01*
X105200D01*
G01X102434Y241900D02*
Y248700D01*
X94166D01*
Y247434D01*
X96300Y245300D01*
X94166Y243166D01*
Y241900D01*
X102434D01*
G01X97900Y267900D02*
Y274100D01*
X101100D01*
Y267900D01*
X97900D01*
G01X105800Y268800D02*
Y275000D01*
X109000D01*
Y268800D01*
X105800D01*
G01X101900Y267900D02*
Y274100D01*
X105100D01*
Y267900D01*
X101900D01*
G01X93900D02*
Y274100D01*
X97100D01*
Y267900D01*
X93900D01*
G01X101500Y326600D02*
Y332800D01*
X104700D01*
Y326600D01*
X101500D01*
G01X96400D02*
Y332800D01*
X99600D01*
Y326600D01*
X96400D01*
G01X108108Y338831D02*
Y336331D01*
X108428Y336831D01*
G01Y338831D02*
X107788D01*
G01X106507Y331917D02*
X106347Y331667D01*
X106160Y331542D01*
X105947Y331500D01*
X105680Y331583D01*
X105493Y331792D01*
X105440Y332042D01*
X105467Y332292D01*
X105573Y332500D01*
X106107Y332917D01*
X106347Y333208D01*
X106507Y333625D01*
X106560Y334000D01*
X105440D01*
G01X102396Y338331D02*
X102236Y338623D01*
X102022Y338789D01*
X101782Y338831D01*
X101569Y338789D01*
X101356Y338581D01*
X101222Y338331D01*
X101196Y338081D01*
X101249Y337789D01*
X101436Y337581D01*
X101622Y337498D01*
X101862D01*
G01X101622D02*
X101462Y337373D01*
X101329Y337164D01*
X101276Y336914D01*
X101329Y336664D01*
X101462Y336456D01*
X101702Y336331D01*
X101942Y336373D01*
X102182Y336539D01*
G01X98239Y335731D02*
Y333231D01*
X99226Y335023D01*
X97892D01*
G01X96097Y338456D02*
X95937Y338664D01*
X95750Y338789D01*
X95510Y338831D01*
X95270Y338748D01*
X95083Y338581D01*
X94950Y338289D01*
X94923Y337956D01*
X94977Y337623D01*
X95110Y337414D01*
X95297Y337248D01*
X95483Y337206D01*
X95670Y337248D01*
X95910Y337414D01*
X95830Y336331D01*
X95110D01*
G01X94507Y333458D02*
X94320Y333167D01*
X94160Y333000D01*
X93947Y332917D01*
X93760Y333000D01*
X93627Y333167D01*
X93520Y333417D01*
X93493Y333708D01*
X93520Y333958D01*
X93627Y334208D01*
X93787Y334417D01*
X93973Y334500D01*
X94187Y334417D01*
X94373Y334167D01*
X94480Y333792D01*
X94507Y333375D01*
X94453Y332833D01*
X94373Y332542D01*
X94240Y332250D01*
X94053Y332042D01*
X93867Y332000D01*
X93680Y332083D01*
X93547Y332292D01*
G01X102100Y407600D02*
Y401400D01*
X98900D01*
Y407600D01*
X102100D01*
G01X106100D02*
Y401400D01*
X102900D01*
Y407600D01*
X106100D01*
G01X110100D02*
Y401400D01*
X106900D01*
Y407600D01*
X110100D01*
G01X96987Y410700D02*
X99413D01*
G01X110500Y411227D02*
Y408987D01*
G01X112125Y410200D02*
X108875D01*
G01X94807Y419500D02*
Y422600D01*
X95573D01*
X95880Y422445D01*
X96110Y422238D01*
X96302Y421928D01*
X96455Y421567D01*
X96493Y421050D01*
X96455Y420533D01*
X96302Y420172D01*
X96110Y419862D01*
X95880Y419655D01*
X95573Y419500D01*
X94807D01*
G01X98750D02*
Y422600D01*
X98290Y421980D01*
G01Y419500D02*
X99210D01*
G01X101773D02*
X101850Y420172D01*
X101965Y420740D01*
X102118Y421257D01*
X102310Y421825D01*
X102617Y422600D01*
X101083D01*
G01X104905Y413231D02*
Y417169D01*
X102937Y415200D01*
X104905Y413231D01*
G01X102543D02*
Y417169D01*
G01X95574Y412550D02*
Y412450D01*
X94924D01*
Y417950D01*
X95624D01*
Y417700D01*
X95224D01*
Y412450D01*
X94474D01*
Y417950D01*
X94974D01*
G01X111774Y412444D02*
X95626D01*
Y417956D01*
X111774D01*
Y412444D01*
G01X97080Y423850D02*
Y430050D01*
X100280D01*
Y423850D01*
X97080D01*
G01X105000Y434645D02*
X168000D01*
G01X113189Y33032D02*
X130905D01*
Y9410D01*
X127559D01*
Y5866D01*
G02X122047Y355I-5512J1D01*
G02X116535Y5866I0J5512D01*
G01Y9410D01*
X113189D01*
Y33032D01*
G01X118100Y43600D02*
Y37400D01*
X114900D01*
Y43600D01*
X118100D01*
G01X118900Y37400D02*
Y43600D01*
X122100D01*
Y37400D01*
X118900D01*
G01X110900D02*
Y43600D01*
X114100D01*
Y37400D01*
X110900D01*
G01X114401Y61363D02*
X108201D01*
G01X125339Y62937D02*
X118929D01*
G01D02*
Y63650D01*
G01X122747Y72669D02*
X119400D01*
X117500Y74869D01*
X115600Y72669D01*
X112253D01*
Y81331D01*
X122747D01*
Y72669D01*
G01X108201Y64563D02*
X114401D01*
G01Y65363D02*
X108201D01*
G01Y68563D02*
X114401D01*
G01X118929Y66450D02*
Y67011D01*
X125319D01*
G01X120162Y90200D02*
X123056Y87951D01*
Y83351D01*
X110064D01*
Y97000D01*
X123056D01*
Y92400D01*
X120162Y90200D01*
G01X119700Y100400D02*
X113500D01*
Y103600D01*
X119700D01*
Y100400D01*
G01Y106000D02*
X113500D01*
Y109200D01*
X119700D01*
Y106000D01*
G01X121884Y99931D02*
X128116D01*
Y110069D01*
X121884D01*
Y99931D01*
G01X114700Y110000D02*
Y114600D01*
G01X110200Y110000D02*
Y114600D01*
G01X120200Y110000D02*
Y114600D01*
G01X110200Y114500D02*
Y114600D01*
X120200D01*
G01Y110000D02*
X110200D01*
G01X115700D02*
Y114600D01*
G01X114700Y116200D02*
Y120800D01*
G01X110200Y116200D02*
Y120800D01*
G01X120200Y116200D02*
Y120800D01*
G01X110200Y120700D02*
Y120800D01*
X120200D01*
G01Y116200D02*
X110200D01*
G01X115700D02*
Y120800D01*
G01X119100Y121900D02*
X112900D01*
Y125100D01*
X119100D01*
Y121900D01*
G01X121900Y115600D02*
X128100D01*
Y112400D01*
X121900D01*
Y115600D01*
G01X121884Y117431D02*
X128116D01*
Y127569D01*
X121884D01*
Y117431D01*
G01X114700Y126200D02*
Y130800D01*
G01X110200Y126200D02*
Y130800D01*
G01X120200Y126200D02*
Y130800D01*
G01X110200Y130700D02*
Y130800D01*
X120200D01*
G01Y126200D02*
X110200D01*
G01X115700D02*
Y130800D01*
G01X121900Y132600D02*
X128100D01*
Y129400D01*
X121900D01*
Y132600D01*
G01X121307Y137200D02*
Y134978D01*
X121460Y134513D01*
X121767Y134203D01*
X122150Y134100D01*
X122533Y134203D01*
X122840Y134513D01*
X122993Y134978D01*
Y137200D01*
G01X124407Y134720D02*
X124637Y134358D01*
X124943Y134152D01*
X125288Y134100D01*
X125595Y134152D01*
X125902Y134410D01*
X126093Y134720D01*
X126132Y135030D01*
X126055Y135392D01*
X125787Y135650D01*
X125518Y135753D01*
X125173D01*
G01X125518D02*
X125748Y135908D01*
X125940Y136167D01*
X126017Y136477D01*
X125940Y136787D01*
X125748Y137045D01*
X125403Y137200D01*
X125058Y137148D01*
X124713Y136942D01*
G01X127507Y134565D02*
X127737Y134307D01*
X128005Y134152D01*
X128350Y134100D01*
X128695Y134203D01*
X128963Y134410D01*
X129155Y134772D01*
X129193Y135185D01*
X129117Y135598D01*
X128925Y135857D01*
X128657Y136063D01*
X128388Y136115D01*
X128120Y136063D01*
X127775Y135857D01*
X127890Y137200D01*
X128925D01*
G01X118943Y220645D02*
Y218423D01*
X119096Y217958D01*
X119403Y217648D01*
X119786Y217545D01*
X120169Y217648D01*
X120476Y217958D01*
X120629Y218423D01*
Y220645D01*
G01X123346Y217545D02*
Y220645D01*
X121928Y218423D01*
X123844D01*
G01X125986Y217545D02*
Y220645D01*
X125526Y220025D01*
G01Y217545D02*
X126446D01*
G01X121931Y244600D02*
Y238400D01*
X118731D01*
Y244600D01*
X121931D01*
G01X116157Y231700D02*
Y229478D01*
X116310Y229013D01*
X116617Y228703D01*
X117000Y228600D01*
X117383Y228703D01*
X117690Y229013D01*
X117843Y229478D01*
Y231700D01*
G01X120560Y228600D02*
Y231700D01*
X119142Y229478D01*
X121058D01*
G01X122548Y228962D02*
X122817Y228703D01*
X123123Y228600D01*
X123430Y228703D01*
X123698Y229013D01*
X123890Y229478D01*
X123967Y229943D01*
Y230512D01*
X123890Y230977D01*
X123698Y231390D01*
X123468Y231597D01*
X123200Y231700D01*
X122893Y231597D01*
X122663Y231390D01*
X122510Y231080D01*
X122433Y230667D01*
X122510Y230305D01*
X122702Y229943D01*
X122932Y229737D01*
X123200Y229685D01*
X123507Y229788D01*
X123737Y230047D01*
X123967Y230512D01*
G01X110800Y245800D02*
X108469Y243469D01*
Y240360D01*
X117131D01*
Y251240D01*
X108469D01*
Y248131D01*
X110800Y245800D01*
G01X109200Y255600D02*
Y261800D01*
X112400D01*
Y255600D01*
X109200D01*
G01X124100Y258300D02*
Y252100D01*
X120900D01*
Y258300D01*
X124100D01*
G01X113200Y256200D02*
Y262400D01*
X116400D01*
Y256200D01*
X113200D01*
G01X118160Y266601D02*
Y272801D01*
X121360D01*
Y266601D01*
X118160D01*
G01X113660D02*
Y272801D01*
X116860D01*
Y266601D01*
X113660D01*
G01X109900Y266400D02*
Y272600D01*
X113100D01*
Y266400D01*
X109900D01*
G01X122660Y266601D02*
Y272801D01*
X125860D01*
Y266601D01*
X122660D01*
G01Y274601D02*
Y280801D01*
X125860D01*
Y274601D01*
X122660D01*
G01X109500Y274600D02*
Y280800D01*
X112700D01*
Y274600D01*
X109500D01*
G01X113660Y274601D02*
Y280801D01*
X116860D01*
Y274601D01*
X113660D01*
G01X118160D02*
Y280801D01*
X121360D01*
Y274601D01*
X118160D01*
G01X123518Y333088D02*
Y326888D01*
X120318D01*
Y333088D01*
X123518D01*
G01X116318Y326888D02*
Y333088D01*
X119518D01*
Y326888D01*
X116318D01*
G01X112318D02*
Y333088D01*
X115518D01*
Y326888D01*
X112318D01*
G01X123400Y344800D02*
X117200D01*
Y348000D01*
X123400D01*
Y344800D01*
G01Y340900D02*
X117200D01*
Y344100D01*
X123400D01*
Y340900D01*
G01X114175Y346231D02*
X113508Y343731D01*
X112841Y346231D01*
G01X113081Y345356D02*
X113935D01*
G01X117200Y351900D02*
X123400D01*
Y348700D01*
X117200D01*
Y351900D01*
G01Y352600D02*
Y358800D01*
X120400D01*
Y352600D01*
X117200D01*
G01X115695Y348248D02*
X115588Y348123D01*
X115508Y347914D01*
X115455Y347623D01*
X115508Y347373D01*
X115615Y347206D01*
X115801Y347081D01*
X116521D01*
Y349581D01*
X115641D01*
X115455Y349414D01*
X115348Y349164D01*
X115295Y348873D01*
X115348Y348581D01*
X115508Y348331D01*
X115695Y348248D01*
X116521D01*
G01X112921Y350238D02*
X113081Y350113D01*
X113268Y350030D01*
X113481D01*
X113721Y350155D01*
X113908Y350363D01*
X114041Y350613D01*
X114148Y351030D01*
X114175Y351405D01*
X114121Y351780D01*
X114041Y352030D01*
X113881Y352280D01*
X113695Y352447D01*
X113508Y352530D01*
X113321D01*
X113135Y352447D01*
X112975Y352322D01*
X112841Y352155D01*
G01X116495Y355880D02*
Y353380D01*
X115961D01*
X115748Y353505D01*
X115588Y353672D01*
X115455Y353922D01*
X115348Y354213D01*
X115321Y354630D01*
X115348Y355047D01*
X115455Y355338D01*
X115588Y355588D01*
X115748Y355755D01*
X115961Y355880D01*
X116495D01*
G01X112975Y358829D02*
X114041D01*
Y356329D01*
X112975D01*
G01X113401Y357537D02*
X114041D01*
G01X120815Y361679D02*
Y359179D01*
X119801D01*
G01X120175Y360387D02*
X120815D01*
G01X116148Y363579D02*
X115615D01*
Y364329D01*
X115775Y364579D01*
X115961Y364746D01*
X116228Y364829D01*
X116495Y364746D01*
X116681Y364579D01*
X116841Y364329D01*
X116948Y364037D01*
X117001Y363704D01*
Y363412D01*
X116948Y363162D01*
X116841Y362871D01*
X116681Y362621D01*
X116521Y362454D01*
X116308Y362329D01*
X116121D01*
X115908Y362412D01*
X115748Y362579D01*
G01X120868Y367978D02*
Y365478D01*
G01X119748D02*
Y367978D01*
G01Y366728D02*
X120868D01*
G01X116841Y370628D02*
X116708Y370878D01*
X116548Y371045D01*
X116361Y371128D01*
X116148Y371045D01*
X115988Y370878D01*
X115828Y370628D01*
X115775Y370295D01*
Y368628D01*
G01X120895Y374277D02*
Y371777D01*
G01X119881D02*
X120895Y373319D01*
G01X119721Y374277D02*
X120441Y372610D01*
G01X116841Y374927D02*
Y377427D01*
X115775D01*
G01X121001Y380577D02*
Y378077D01*
X120308Y380160D01*
X119615Y378077D01*
Y380577D01*
G01X116921Y383726D02*
Y381226D01*
X115695Y383726D01*
Y381226D01*
G01X120841Y386876D02*
Y384376D01*
X120201D01*
X119988Y384501D01*
X119828Y384793D01*
X119775Y385126D01*
X119828Y385459D01*
X119961Y385709D01*
X120201Y385834D01*
X120841D01*
G01X116841Y390025D02*
Y387525D01*
X116175D01*
X115961Y387650D01*
X115828Y387817D01*
X115775Y388150D01*
X115828Y388483D01*
X115988Y388692D01*
X116175Y388817D01*
X116841D01*
G01X116175D02*
X115775Y390025D01*
G01X120308Y390675D02*
Y393175D01*
G01X120921Y390675D02*
X119695D01*
G01X118100Y407700D02*
Y401500D01*
X114900D01*
Y407700D01*
X118100D01*
G01X120700Y400900D02*
Y394700D01*
X117500D01*
Y400900D01*
X120700D01*
G01X114100Y407600D02*
Y401400D01*
X110900D01*
Y407600D01*
X114100D01*
G01X120600Y413400D02*
X114400D01*
Y416600D01*
X120600D01*
Y413400D01*
G01X121082Y437895D02*
X120929Y437740D01*
X120814Y437481D01*
X120737Y437120D01*
X120814Y436810D01*
X120967Y436603D01*
X121236Y436448D01*
X122271D01*
Y439548D01*
X121006D01*
X120737Y439341D01*
X120584Y439031D01*
X120507Y438670D01*
X120584Y438308D01*
X120814Y437998D01*
X121082Y437895D01*
X122271D01*
G01X117829Y439548D02*
Y436448D01*
X119247Y438670D01*
X117331D01*
G01X116032Y438928D02*
X115802Y439290D01*
X115496Y439496D01*
X115151Y439548D01*
X114844Y439496D01*
X114537Y439238D01*
X114346Y438928D01*
X114307Y438618D01*
X114384Y438256D01*
X114652Y437998D01*
X114921Y437895D01*
X115266D01*
G01X114921D02*
X114691Y437740D01*
X114499Y437481D01*
X114422Y437171D01*
X114499Y436861D01*
X114691Y436603D01*
X115036Y436448D01*
X115381Y436500D01*
X115726Y436706D01*
G01X135937Y14931D02*
X138159D01*
X138624Y15084D01*
X138934Y15391D01*
X139037Y15774D01*
X138934Y16157D01*
X138624Y16464D01*
X138159Y16617D01*
X135937D01*
G01X138624Y18069D02*
X138882Y18376D01*
X139037Y18721D01*
Y19027D01*
X138882Y19334D01*
X138624Y19564D01*
X138262Y19679D01*
X137900Y19602D01*
X137590Y19411D01*
X137384Y19066D01*
X137280Y18606D01*
X137074Y18337D01*
X136712Y18222D01*
X136350Y18299D01*
X136092Y18491D01*
X135937Y18759D01*
Y19027D01*
X136040Y19296D01*
X136299Y19526D01*
G01X137384Y22281D02*
X137229Y22434D01*
X136970Y22549D01*
X136609Y22626D01*
X136299Y22549D01*
X136092Y22396D01*
X135937Y22127D01*
Y21092D01*
X139037D01*
Y22357D01*
X138830Y22626D01*
X138520Y22779D01*
X138159Y22856D01*
X137797Y22779D01*
X137487Y22549D01*
X137384Y22281D01*
Y21092D01*
G01X138417Y24231D02*
X138779Y24461D01*
X138985Y24767D01*
X139037Y25112D01*
X138985Y25419D01*
X138727Y25726D01*
X138417Y25917D01*
X138107Y25956D01*
X137745Y25879D01*
X137487Y25611D01*
X137384Y25342D01*
Y24997D01*
G01Y25342D02*
X137229Y25572D01*
X136970Y25764D01*
X136660Y25841D01*
X136350Y25764D01*
X136092Y25572D01*
X135937Y25227D01*
X135989Y24882D01*
X136195Y24537D01*
G01X139140Y28174D02*
X139089Y28097D01*
X138985D01*
X138934Y28174D01*
X138985Y28251D01*
X139089D01*
X139140Y28174D01*
G01X135937Y31274D02*
X136040Y30967D01*
X136299Y30737D01*
X136609Y30584D01*
X137022Y30469D01*
X137487Y30431D01*
X137952Y30469D01*
X138365Y30584D01*
X138675Y30737D01*
X138934Y30967D01*
X139037Y31274D01*
X138934Y31581D01*
X138675Y31811D01*
X138365Y31964D01*
X137952Y32079D01*
X137487Y32117D01*
X137022Y32079D01*
X136609Y31964D01*
X136299Y31811D01*
X136040Y31581D01*
X135937Y31274D01*
G01X135650Y34000D02*
X135343Y34052D01*
X135075Y34258D01*
X134845Y34568D01*
X134692Y34930D01*
X134615Y35343D01*
Y35757D01*
X134692Y36170D01*
X134845Y36532D01*
X135075Y36842D01*
X135343Y37048D01*
X135650Y37100D01*
X135957Y37048D01*
X136225Y36842D01*
X136455Y36532D01*
X136608Y36170D01*
X136685Y35757D01*
Y35343D01*
X136608Y34930D01*
X136455Y34568D01*
X136225Y34258D01*
X135957Y34052D01*
X135650Y34000D01*
G01X135957Y34827D02*
X136417Y34000D01*
G01X138098Y34362D02*
X138367Y34103D01*
X138673Y34000D01*
X138980Y34103D01*
X139248Y34413D01*
X139440Y34878D01*
X139517Y35343D01*
Y35912D01*
X139440Y36377D01*
X139248Y36790D01*
X139018Y36997D01*
X138750Y37100D01*
X138443Y36997D01*
X138213Y36790D01*
X138060Y36480D01*
X137983Y36067D01*
X138060Y35705D01*
X138252Y35343D01*
X138482Y35137D01*
X138750Y35085D01*
X139057Y35188D01*
X139287Y35447D01*
X139517Y35912D01*
G01X123307Y33700D02*
Y36800D01*
X124073D01*
X124380Y36645D01*
X124610Y36438D01*
X124802Y36128D01*
X124955Y35767D01*
X124993Y35250D01*
X124955Y34733D01*
X124802Y34372D01*
X124610Y34062D01*
X124380Y33855D01*
X124073Y33700D01*
X123307D01*
G01X127250D02*
Y36800D01*
X126790Y36180D01*
G01Y33700D02*
X127710D01*
G01X129507Y34320D02*
X129737Y33958D01*
X130043Y33752D01*
X130388Y33700D01*
X130695Y33752D01*
X131002Y34010D01*
X131193Y34320D01*
X131232Y34630D01*
X131155Y34992D01*
X130887Y35250D01*
X130618Y35353D01*
X130273D01*
G01X130618D02*
X130848Y35508D01*
X131040Y35767D01*
X131117Y36077D01*
X131040Y36387D01*
X130848Y36645D01*
X130503Y36800D01*
X130158Y36748D01*
X129813Y36542D01*
G01X123753Y46231D02*
X127100D01*
X129000Y44031D01*
X130900Y46231D01*
X134247D01*
Y37569D01*
X123753D01*
Y46231D01*
G01X132100Y48400D02*
X125900D01*
Y51600D01*
X132100D01*
Y48400D01*
G01X124900Y55900D02*
X131100D01*
Y52700D01*
X124900D01*
Y55900D01*
G01X131807Y58600D02*
Y56378D01*
X131960Y55913D01*
X132267Y55603D01*
X132650Y55500D01*
X133033Y55603D01*
X133340Y55913D01*
X133493Y56378D01*
Y58600D01*
G01X134907Y56120D02*
X135137Y55758D01*
X135443Y55552D01*
X135788Y55500D01*
X136095Y55552D01*
X136402Y55810D01*
X136593Y56120D01*
X136632Y56430D01*
X136555Y56792D01*
X136287Y57050D01*
X136018Y57153D01*
X135673D01*
G01X136018D02*
X136248Y57308D01*
X136440Y57567D01*
X136517Y57877D01*
X136440Y58187D01*
X136248Y58445D01*
X135903Y58600D01*
X135558Y58548D01*
X135213Y58342D01*
G01X138850Y55500D02*
X139118Y55552D01*
X139425Y55707D01*
X139617Y55965D01*
X139693Y56327D01*
X139617Y56688D01*
X139387Y56998D01*
X139042Y57153D01*
X138658D01*
X138428Y57257D01*
X138237Y57515D01*
X138160Y57877D01*
X138275Y58238D01*
X138543Y58497D01*
X138850Y58600D01*
X139157Y58497D01*
X139425Y58238D01*
X139540Y57877D01*
X139463Y57515D01*
X139272Y57257D01*
X139042Y57153D01*
X138658D01*
X138313Y56998D01*
X138083Y56688D01*
X138007Y56327D01*
X138083Y55965D01*
X138275Y55707D01*
X138582Y55552D01*
X138850Y55500D01*
G01X127800Y84100D02*
Y77900D01*
X124600D01*
Y84100D01*
X127800D01*
G01X129174Y78816D02*
X132274D01*
X131654Y79276D01*
G01X129174D02*
Y78356D01*
G01X129794Y76559D02*
X129432Y76329D01*
X129226Y76023D01*
X129174Y75678D01*
X129226Y75371D01*
X129484Y75064D01*
X129794Y74873D01*
X130104Y74834D01*
X130466Y74911D01*
X130724Y75179D01*
X130827Y75448D01*
Y75793D01*
G01Y75448D02*
X130982Y75218D01*
X131241Y75026D01*
X131551Y74949D01*
X131861Y75026D01*
X132119Y75218D01*
X132274Y75563D01*
X132222Y75908D01*
X132016Y76253D01*
G01X137598Y75466D02*
Y71142D01*
X142207D01*
G01X127833Y85507D02*
X124733D01*
Y86273D01*
X124888Y86580D01*
X125095Y86810D01*
X125405Y87002D01*
X125766Y87155D01*
X126283Y87193D01*
X126800Y87155D01*
X127161Y87002D01*
X127471Y86810D01*
X127678Y86580D01*
X127833Y86273D01*
Y85507D01*
G01Y89450D02*
X124733D01*
X125353Y88990D01*
G01X127833D02*
Y89910D01*
G01X125250Y91822D02*
X124940Y92052D01*
X124785Y92320D01*
X124733Y92627D01*
X124836Y93010D01*
X125095Y93278D01*
X125405Y93355D01*
X125715Y93317D01*
X125973Y93163D01*
X126490Y92397D01*
X126851Y92052D01*
X127368Y91822D01*
X127833Y91745D01*
Y93355D01*
G01X128933Y103007D02*
X131155D01*
X131620Y103160D01*
X131930Y103467D01*
X132033Y103850D01*
X131930Y104233D01*
X131620Y104540D01*
X131155Y104693D01*
X128933D01*
G01X131413Y106107D02*
X131775Y106337D01*
X131981Y106643D01*
X132033Y106988D01*
X131981Y107295D01*
X131723Y107602D01*
X131413Y107793D01*
X131103Y107832D01*
X130741Y107755D01*
X130483Y107487D01*
X130380Y107218D01*
Y106873D01*
G01Y107218D02*
X130225Y107448D01*
X129966Y107640D01*
X129656Y107717D01*
X129346Y107640D01*
X129088Y107448D01*
X128933Y107103D01*
X128985Y106758D01*
X129191Y106413D01*
G01X132033Y110510D02*
X128933D01*
X131155Y109092D01*
Y111008D01*
G01X136683Y132920D02*
X136875Y132610D01*
X137105Y132403D01*
X137373Y132300D01*
X137680Y132403D01*
X137910Y132610D01*
X138140Y132920D01*
X138217Y133333D01*
Y135400D01*
G01X140550Y132300D02*
X140818Y132352D01*
X141125Y132507D01*
X141317Y132765D01*
X141393Y133127D01*
X141317Y133488D01*
X141087Y133798D01*
X140742Y133953D01*
X140358D01*
X140128Y134057D01*
X139937Y134315D01*
X139860Y134677D01*
X139975Y135038D01*
X140243Y135297D01*
X140550Y135400D01*
X140857Y135297D01*
X141125Y135038D01*
X141240Y134677D01*
X141163Y134315D01*
X140972Y134057D01*
X140742Y133953D01*
X140358D01*
X140013Y133798D01*
X139783Y133488D01*
X139707Y133127D01*
X139783Y132765D01*
X139975Y132507D01*
X140282Y132352D01*
X140550Y132300D01*
G01X142207Y130590D02*
X137598D01*
Y126266D01*
G01X127900Y139400D02*
Y145600D01*
X131100D01*
Y139400D01*
X127900D01*
G01X135925Y139227D02*
Y145427D01*
X139125D01*
Y139227D01*
X135925D01*
G01X131900Y139400D02*
Y145600D01*
X135100D01*
Y139400D01*
X131900D01*
G01X122700Y151157D02*
X124922D01*
X125387Y151310D01*
X125697Y151617D01*
X125800Y152000D01*
X125697Y152383D01*
X125387Y152690D01*
X124922Y152843D01*
X122700D01*
G01X125800Y155560D02*
X122700D01*
X124922Y154142D01*
Y156058D01*
G01X125180Y157357D02*
X125542Y157587D01*
X125748Y157893D01*
X125800Y158238D01*
X125748Y158545D01*
X125490Y158852D01*
X125180Y159043D01*
X124870Y159082D01*
X124508Y159005D01*
X124250Y158737D01*
X124147Y158468D01*
Y158123D01*
G01Y158468D02*
X123992Y158698D01*
X123733Y158890D01*
X123423Y158967D01*
X123113Y158890D01*
X122855Y158698D01*
X122700Y158353D01*
X122752Y158008D01*
X122958Y157663D01*
G01X130000Y158300D02*
X127496Y160800D01*
Y166300D01*
X139504D01*
Y150300D01*
X127496D01*
Y155800D01*
X130000Y158300D01*
G01X134500Y185800D02*
Y179600D01*
X131300D01*
Y185800D01*
X134500D01*
G01X131400Y171900D02*
Y178100D01*
X134600D01*
Y171900D01*
X131400D01*
G01X127400D02*
Y178100D01*
X130600D01*
Y171900D01*
X127400D01*
G01X126400Y190783D02*
X123300D01*
Y191703D01*
X123455Y192010D01*
X123817Y192240D01*
X124230Y192317D01*
X124643Y192240D01*
X124953Y192048D01*
X125108Y191703D01*
Y190783D01*
G01X126400Y194650D02*
X123300D01*
X123920Y194190D01*
G01X126400D02*
Y195110D01*
G01X123300Y196792D02*
X126400Y197750D01*
X123300Y198708D01*
G01X126400Y200850D02*
X126348Y201118D01*
X126193Y201425D01*
X125935Y201617D01*
X125573Y201693D01*
X125212Y201617D01*
X124902Y201387D01*
X124747Y201042D01*
Y200658D01*
X124643Y200428D01*
X124385Y200237D01*
X124023Y200160D01*
X123662Y200275D01*
X123403Y200543D01*
X123300Y200850D01*
X123403Y201157D01*
X123662Y201425D01*
X124023Y201540D01*
X124385Y201463D01*
X124643Y201272D01*
X124747Y201042D01*
Y200658D01*
X124902Y200313D01*
X125212Y200083D01*
X125573Y200007D01*
X125935Y200083D01*
X126193Y200275D01*
X126348Y200582D01*
X126400Y200850D01*
G01X127433Y202800D02*
Y205100D01*
G01X126400Y206092D02*
X123300Y207050D01*
X126400Y208008D01*
G01X125315Y207663D02*
Y206437D01*
G01X123300Y209307D02*
X125522D01*
X125987Y209460D01*
X126297Y209767D01*
X126400Y210150D01*
X126297Y210533D01*
X125987Y210840D01*
X125522Y210993D01*
X123300D01*
G01X126400Y212445D02*
X123300Y214055D01*
G01Y212445D02*
X126400Y214055D01*
G01X134300Y207500D02*
X127700D01*
Y220500D01*
X134300D01*
Y207500D01*
G01X138600Y199900D02*
X132400D01*
Y203100D01*
X138600D01*
Y199900D01*
G01X139600Y212600D02*
Y206400D01*
X136400D01*
Y212600D01*
X139600D01*
G01X127700Y214000D02*
X134300D01*
G01X133998Y229292D02*
Y223092D01*
X130798D01*
Y229292D01*
X133998D01*
G01X130320Y229290D02*
Y223090D01*
X127120D01*
Y229290D01*
X130320D01*
G01X123876Y250201D02*
X129100D01*
X131100Y248000D01*
X133100Y250201D01*
X138324D01*
Y237799D01*
X123876D01*
Y250201D01*
G01X124900Y252100D02*
Y258300D01*
X128100D01*
Y252100D01*
X124900D01*
G01X135100D02*
X128900D01*
Y255300D01*
X135100D01*
Y252100D01*
G01X134300Y260300D02*
X128100D01*
Y263500D01*
X134300D01*
Y260300D01*
G01X122900Y259600D02*
Y265800D01*
X126100D01*
Y259600D01*
X122900D01*
G01X127160Y266601D02*
Y272801D01*
X130360D01*
Y266601D01*
X127160D01*
G01X131400Y266400D02*
Y272600D01*
X134600D01*
Y266400D01*
X131400D01*
G01X127160Y274601D02*
Y280801D01*
X130360D01*
Y274601D01*
X127160D01*
G01X139518Y333088D02*
Y326888D01*
X136318D01*
Y333088D01*
X139518D01*
G01X127518D02*
Y326888D01*
X124318D01*
Y333088D01*
X127518D01*
G01X128318Y326888D02*
Y333088D01*
X131518D01*
Y326888D01*
X128318D01*
G01X132318D02*
Y333088D01*
X135518D01*
Y326888D01*
X132318D01*
G01X150899Y339980D02*
X125394D01*
Y340999D01*
G01Y344099D02*
Y385472D01*
G01X126507Y337800D02*
Y335578D01*
X126660Y335113D01*
X126967Y334803D01*
X127350Y334700D01*
X127733Y334803D01*
X128040Y335113D01*
X128193Y335578D01*
Y337800D01*
G01X129722Y337283D02*
X129952Y337593D01*
X130220Y337748D01*
X130527Y337800D01*
X130910Y337697D01*
X131178Y337438D01*
X131255Y337128D01*
X131217Y336818D01*
X131063Y336560D01*
X130297Y336043D01*
X129952Y335682D01*
X129722Y335165D01*
X129645Y334700D01*
X131255D01*
G01X132707Y335165D02*
X132937Y334907D01*
X133205Y334752D01*
X133550Y334700D01*
X133895Y334803D01*
X134163Y335010D01*
X134355Y335372D01*
X134393Y335785D01*
X134317Y336198D01*
X134125Y336457D01*
X133857Y336663D01*
X133588Y336715D01*
X133320Y336663D01*
X132975Y336457D01*
X133090Y337800D01*
X134125D01*
G01X141500Y346700D02*
X135300D01*
Y349900D01*
X141500D01*
Y346700D01*
G01Y350300D02*
X135300D01*
Y353500D01*
X141500D01*
Y350300D01*
G01X125394Y358129D02*
Y385472D01*
G01Y358129D02*
X185630D01*
G01X139513Y385473D02*
X134844Y392142D01*
Y400434D01*
X176182D01*
Y370512D01*
X134844D01*
Y378804D01*
X139513Y385473D01*
G01X125394Y385472D02*
Y418229D01*
G01Y412815D02*
Y385472D01*
G01X136062Y413572D02*
Y416672D01*
X135602Y416052D01*
G01Y413572D02*
X136522D01*
G01X138434Y414864D02*
X138702Y415225D01*
X138932Y415432D01*
X139239Y415535D01*
X139507Y415432D01*
X139699Y415225D01*
X139852Y414915D01*
X139890Y414554D01*
X139852Y414244D01*
X139699Y413934D01*
X139469Y413675D01*
X139200Y413572D01*
X138894Y413675D01*
X138625Y413985D01*
X138472Y414450D01*
X138434Y414967D01*
X138510Y415639D01*
X138625Y416000D01*
X138817Y416362D01*
X139085Y416620D01*
X139354Y416672D01*
X139622Y416569D01*
X139814Y416310D01*
G01X125394Y412815D02*
X185630D01*
G01X137700Y427400D02*
X131500D01*
Y430600D01*
X137700D01*
Y427400D01*
G01X130900Y430600D02*
Y424400D01*
X127700D01*
Y430600D01*
X130900D01*
G01X143482Y437895D02*
X143329Y437740D01*
X143214Y437481D01*
X143137Y437120D01*
X143214Y436810D01*
X143367Y436603D01*
X143636Y436448D01*
X144671D01*
Y439548D01*
X143406D01*
X143137Y439341D01*
X142984Y439031D01*
X142907Y438670D01*
X142984Y438308D01*
X143214Y437998D01*
X143482Y437895D01*
X144671D01*
G01X140229Y439548D02*
Y436448D01*
X141647Y438670D01*
X139731D01*
G01X138317Y436965D02*
X138087Y436655D01*
X137819Y436500D01*
X137512Y436448D01*
X137129Y436551D01*
X136861Y436810D01*
X136784Y437120D01*
X136822Y437430D01*
X136976Y437688D01*
X137742Y438205D01*
X138087Y438566D01*
X138317Y439083D01*
X138394Y439548D01*
X136784D01*
G01X152693Y-618936D02*
Y-626936D01*
X156693D01*
G01X164493D02*
Y-621603D01*
G01Y-622536D02*
X164093Y-622003D01*
X163493Y-621736D01*
X162793Y-621603D01*
X162093Y-621869D01*
X161493Y-622403D01*
X161093Y-623203D01*
X160893Y-624269D01*
X161093Y-625336D01*
X161493Y-626136D01*
X162093Y-626669D01*
X162793Y-626936D01*
X163493Y-626803D01*
X164093Y-626403D01*
X164493Y-625870D01*
G01X168593Y-629336D02*
X169193Y-629603D01*
X169993Y-629336D01*
X170493Y-628803D01*
X170893Y-628136D01*
X171493Y-626003D01*
X172793Y-621603D01*
G01X169593D02*
X171493Y-626003D01*
G01X177193Y-623336D02*
X180393D01*
X180093Y-622403D01*
X179593Y-621869D01*
X178893Y-621603D01*
X178193Y-621736D01*
X177593Y-622136D01*
X177193Y-623069D01*
X176993Y-623870D01*
Y-624669D01*
X177193Y-625469D01*
X177693Y-626269D01*
X178293Y-626803D01*
X178993Y-626936D01*
X179693Y-626669D01*
X180393Y-625870D01*
G01X185293Y-626936D02*
Y-621603D01*
G01Y-622669D02*
X185793Y-622136D01*
X186293Y-621736D01*
X186993Y-621603D01*
X187493Y-621736D01*
X188093Y-622136D01*
G01X140638Y38177D02*
Y-1575D01*
X197331D01*
Y38177D01*
G01X140638Y60365D02*
Y51427D01*
G01X149016Y75066D02*
Y126666D01*
G01X140738Y65564D02*
X140930Y65254D01*
X141160Y65047D01*
X141428Y64944D01*
X141735Y65047D01*
X141965Y65254D01*
X142195Y65564D01*
X142272Y65977D01*
Y68044D01*
G01X143877Y67527D02*
X144107Y67837D01*
X144375Y67992D01*
X144682Y68044D01*
X145065Y67941D01*
X145333Y67682D01*
X145410Y67372D01*
X145372Y67062D01*
X145218Y66804D01*
X144452Y66287D01*
X144107Y65926D01*
X143877Y65409D01*
X143800Y64944D01*
X145410D01*
G01X156586Y63386D02*
X145402D01*
G01X150845Y84400D02*
X155845Y85983D01*
X150845Y87566D01*
G01X153345Y91463D02*
Y92730D01*
X154845D01*
X155345Y92350D01*
X155678Y91906D01*
X155845Y91273D01*
X155678Y90640D01*
X155345Y90196D01*
X154845Y89816D01*
X154262Y89563D01*
X153595Y89436D01*
X153012D01*
X152512Y89563D01*
X151928Y89816D01*
X151428Y90196D01*
X151095Y90576D01*
X150845Y91083D01*
Y91526D01*
X151012Y92033D01*
X151345Y92413D01*
G01X155845Y94600D02*
X150845Y96183D01*
X155845Y97766D01*
G01X154095Y97196D02*
Y95170D01*
G01X147100Y145100D02*
Y138900D01*
X143900D01*
Y145100D01*
X147100D01*
G01X154100Y140400D02*
X147900D01*
Y143600D01*
X154100D01*
Y140400D01*
G01X149987Y154815D02*
Y148615D01*
X146787D01*
Y154815D01*
X149987D01*
G01X139900Y138900D02*
Y145100D01*
X143100D01*
Y138900D01*
X139900D01*
G01X150834Y148615D02*
Y154815D01*
X154034D01*
Y148615D01*
X150834D01*
G01X150000Y169200D02*
Y163000D01*
X146800D01*
Y169200D01*
X150000D01*
G01X145100Y173600D02*
X138900D01*
Y176800D01*
X145100D01*
Y173600D01*
G01X145110Y177560D02*
X138910D01*
Y180760D01*
X145110D01*
Y177560D01*
G01X153194Y180994D02*
X146994D01*
Y184194D01*
X153194D01*
Y180994D01*
G01X149970Y176850D02*
Y170650D01*
X146770D01*
Y176850D01*
X149970D01*
G01X145976Y188954D02*
X152176D01*
Y185754D01*
X145976D01*
Y188954D01*
G01X143750Y188675D02*
Y182475D01*
X140550D01*
Y188675D01*
X143750D01*
G01X148000Y212300D02*
Y205700D01*
G01X141500D02*
Y212300D01*
X154500D01*
Y205700D01*
X141500D01*
G01X138360Y226226D02*
X150368D01*
G01X138360Y214218D02*
X150368D01*
G01X140464Y226226D02*
X138360D01*
Y225422D01*
G01X147764Y214218D02*
X150368D01*
G01Y225422D02*
Y226226D01*
X147864D01*
G01X138360Y215022D02*
Y214218D01*
X140664D01*
G01X150368D02*
Y215022D01*
G01X155100Y233600D02*
Y227400D01*
X151900D01*
Y233600D01*
X155100D01*
G01X151340Y244350D02*
X157540D01*
Y241150D01*
X151340D01*
Y244350D01*
G01X151100Y234100D02*
Y227900D01*
X147900D01*
Y234100D01*
X151100D01*
G01X139900Y236900D02*
Y243100D01*
X143100D01*
Y236900D01*
X139900D01*
G01X147200Y240000D02*
Y233800D01*
X144000D01*
Y240000D01*
X147200D01*
G01X149600Y268957D02*
X151822D01*
X152287Y269110D01*
X152597Y269417D01*
X152700Y269800D01*
X152597Y270183D01*
X152287Y270490D01*
X151822Y270643D01*
X149600D01*
G01X152700Y272900D02*
X149600D01*
X150220Y272440D01*
G01X152700D02*
Y273360D01*
G01X152235Y275157D02*
X152493Y275387D01*
X152648Y275655D01*
X152700Y276000D01*
X152597Y276345D01*
X152390Y276613D01*
X152028Y276805D01*
X151615Y276843D01*
X151202Y276767D01*
X150943Y276575D01*
X150737Y276307D01*
X150685Y276038D01*
X150737Y275770D01*
X150943Y275425D01*
X149600Y275540D01*
Y276575D01*
G01X143900Y280300D02*
Y274100D01*
X140700D01*
Y280300D01*
X143900D01*
G01X141815Y289705D02*
X148327D01*
Y294881D01*
G01Y300781D02*
Y309481D01*
G01X155518Y333088D02*
Y326888D01*
X152318D01*
Y333088D01*
X155518D01*
G01X143518D02*
Y326888D01*
X140318D01*
Y333088D01*
X143518D01*
G01X144318Y326888D02*
Y333088D01*
X147518D01*
Y326888D01*
X144318D01*
G01X148318D02*
Y333088D01*
X151518D01*
Y326888D01*
X148318D01*
G01X143105Y317855D02*
X142815D01*
G01X145545Y353248D02*
Y347048D01*
X142345D01*
Y353248D01*
X145545D01*
G01X149500Y353200D02*
Y347000D01*
X146300D01*
Y353200D01*
X149500D01*
G01X144600Y424100D02*
Y417900D01*
X141400D01*
Y424100D01*
X144600D01*
G01X151180Y417650D02*
X144980D01*
Y420850D01*
X151180D01*
Y417650D01*
G01X155100Y427400D02*
X148900D01*
Y430600D01*
X155100D01*
Y427400D01*
G01X149000Y434200D02*
X155200D01*
Y431000D01*
X149000D01*
Y434200D01*
G01X146800Y434050D02*
Y427850D01*
X143600D01*
Y434050D01*
X146800D01*
G01X138300Y427400D02*
Y433600D01*
X141500D01*
Y427400D01*
X138300D01*
G01X164093Y-650870D02*
X164893Y-651536D01*
X165793Y-651936D01*
X166593D01*
X167393Y-651536D01*
X167993Y-650870D01*
X168293Y-649936D01*
X168093Y-649003D01*
X167593Y-648203D01*
X166693Y-647669D01*
X165493Y-647403D01*
X164793Y-646869D01*
X164493Y-645936D01*
X164693Y-645003D01*
X165193Y-644336D01*
X165893Y-643936D01*
X166593D01*
X167293Y-644203D01*
X167893Y-644869D01*
G01X172993Y-643936D02*
X175393D01*
G01X174193D02*
Y-651936D01*
G01X172993D02*
X175393D01*
G01X180193Y-643936D02*
Y-651936D01*
X184193D01*
G01X187993D02*
Y-643936D01*
G01X191793D02*
X187993Y-648870D01*
G01X192393Y-651936D02*
X189693Y-646603D01*
G01X196893Y-649269D02*
X199493D01*
G01X206193Y-643936D02*
Y-651936D01*
G01X203893Y-643936D02*
X208493D01*
G01X214193Y-651936D02*
X213393Y-651803D01*
X212693Y-651269D01*
X212093Y-650469D01*
X211693Y-649536D01*
X211493Y-648469D01*
Y-647403D01*
X211693Y-646336D01*
X212093Y-645403D01*
X212693Y-644603D01*
X213393Y-644069D01*
X214193Y-643936D01*
X214993Y-644069D01*
X215693Y-644603D01*
X216293Y-645403D01*
X216693Y-646336D01*
X216893Y-647403D01*
Y-648469D01*
X216693Y-649536D01*
X216293Y-650469D01*
X215693Y-651269D01*
X214993Y-651803D01*
X214193Y-651936D01*
G01X220193D02*
Y-643936D01*
X222593D01*
X223393Y-644336D01*
X223993Y-645269D01*
X224193Y-646336D01*
X223993Y-647403D01*
X223493Y-648203D01*
X222593Y-648603D01*
X220193D01*
G01X161650Y74716D02*
Y68484D01*
X162200D01*
G01X168300Y74716D02*
X165400D01*
G01X162200D02*
X161650D01*
G01X165200Y68484D02*
X168000D01*
G01X168975Y63386D02*
X163214D01*
G01X165273Y90330D02*
Y84130D01*
G01X162073D02*
Y90330D01*
G01X161273D02*
Y84130D01*
G01X158073D02*
Y90330D01*
G01X165061Y93244D02*
Y81244D01*
X163599D01*
G01X159829D02*
X158261D01*
Y93244D01*
X160159D01*
G01X153700Y99700D02*
Y105900D01*
X156900D01*
Y99700D01*
X153700D01*
G01X163399Y93244D02*
X165061D01*
G01X174700Y109502D02*
Y97298D01*
X158700D01*
Y109502D01*
X174700D01*
G01X153930Y117520D02*
Y123720D01*
X157130D01*
Y117520D01*
X153930D01*
G01X167016Y118426D02*
Y124626D01*
X170216D01*
Y118426D01*
X167016D01*
G01X162800Y118400D02*
Y124600D01*
X166000D01*
Y118400D01*
X162800D01*
G01X160720Y123720D02*
Y117520D01*
X157520D01*
Y123720D01*
X160720D01*
G01X167900Y111200D02*
X161700D01*
Y114400D01*
X167900D01*
Y111200D01*
G01X158100Y137100D02*
Y130900D01*
X154900D01*
Y137100D01*
X158100D01*
G01X166400Y133400D02*
Y139600D01*
X169600D01*
Y133400D01*
X166400D01*
G01X162776Y168000D02*
Y141029D01*
X176300D01*
G01X158857Y140909D02*
Y147109D01*
X162057D01*
Y140909D01*
X158857D01*
G01X154830Y140881D02*
Y147081D01*
X158030D01*
Y140881D01*
X154830D01*
G01X161005Y151477D02*
X154805D01*
Y154677D01*
X161005D01*
Y151477D01*
G01X154300Y159900D02*
X160500D01*
Y156700D01*
X154300D01*
Y159900D01*
G01X154000Y165000D02*
X160200D01*
Y161800D01*
X154000D01*
Y165000D01*
G01X154600Y168700D02*
X160800D01*
Y165500D01*
X154600D01*
Y168700D01*
G01X162776Y173300D02*
Y171700D01*
G01Y179800D02*
Y176900D01*
G01X160209Y181044D02*
X154009D01*
Y184244D01*
X160209D01*
Y181044D01*
G01X160316Y177079D02*
X154116D01*
Y180279D01*
X160316D01*
Y177079D01*
G01X160300Y173200D02*
X154100D01*
Y176400D01*
X160300D01*
Y173200D01*
G01X154100Y172600D02*
X160300D01*
Y169400D01*
X154100D01*
Y172600D01*
G01X162776Y226389D02*
Y183300D01*
G01X160350Y185754D02*
X154150D01*
Y188954D01*
X160350D01*
Y185754D01*
G01X160400Y190100D02*
X154200D01*
Y193300D01*
X160400D01*
Y190100D01*
G01X152700Y197300D02*
X158900D01*
Y194100D01*
X152700D01*
Y197300D01*
G01X158900Y201000D02*
Y207200D01*
X162100D01*
Y201000D01*
X158900D01*
G01X155257Y214168D02*
X161457D01*
Y210968D01*
X155257D01*
Y214168D01*
G01X154428Y215119D02*
Y221319D01*
X157628D01*
Y215119D01*
X154428D01*
G01X161632Y221319D02*
Y215119D01*
X158432D01*
Y221319D01*
X161632D01*
G01X161100Y222400D02*
X154900D01*
Y225600D01*
X161100D01*
Y222400D01*
G01X216073Y247721D02*
X162776D01*
Y232077D01*
G01X155900Y227400D02*
Y233600D01*
X159100D01*
Y227400D01*
X155900D01*
G01X155373Y247911D02*
Y254111D01*
X158573D01*
Y247911D01*
X155373D01*
G01X159113Y255929D02*
Y262129D01*
X162313D01*
Y255929D01*
X159113D01*
G01X166401Y262061D02*
Y255861D01*
X163201D01*
Y262061D01*
X166401D01*
G01X162573Y254111D02*
Y247911D01*
X159373D01*
Y254111D01*
X162573D01*
G01X155113Y255929D02*
Y262129D01*
X158313D01*
Y255929D01*
X155113D01*
G01X163413Y247911D02*
Y254111D01*
X166613D01*
Y247911D01*
X163413D01*
G01X162400Y284200D02*
Y270800D01*
G01X153600Y276500D02*
Y270800D01*
G01X162400D02*
X153600D01*
G01X166773Y270100D02*
X169013D01*
G01X167800Y271725D02*
Y268475D01*
G01X160643Y265876D02*
Y268976D01*
X161409D01*
X161716Y268821D01*
X161946Y268614D01*
X162138Y268304D01*
X162291Y267943D01*
X162329Y267426D01*
X162291Y266909D01*
X162138Y266548D01*
X161946Y266238D01*
X161716Y266031D01*
X161409Y265876D01*
X160643D01*
G01X164586D02*
X164854Y265928D01*
X165161Y266083D01*
X165353Y266341D01*
X165429Y266703D01*
X165353Y267064D01*
X165123Y267374D01*
X164778Y267529D01*
X164394D01*
X164164Y267633D01*
X163973Y267891D01*
X163896Y268253D01*
X164011Y268614D01*
X164279Y268873D01*
X164586Y268976D01*
X164893Y268873D01*
X165161Y268614D01*
X165276Y268253D01*
X165199Y267891D01*
X165008Y267633D01*
X164778Y267529D01*
X164394D01*
X164049Y267374D01*
X163819Y267064D01*
X163743Y266703D01*
X163819Y266341D01*
X164011Y266083D01*
X164318Y265928D01*
X164586Y265876D01*
G01X163928Y280711D02*
Y283811D01*
G01Y282313D02*
X164120Y282571D01*
X164312Y282726D01*
X164618Y282778D01*
X164848Y282726D01*
X165117Y282519D01*
X165232Y282209D01*
Y280711D01*
G01X167105Y282106D02*
X168332D01*
X168217Y282468D01*
X168025Y282674D01*
X167757Y282778D01*
X167488Y282726D01*
X167258Y282571D01*
X167105Y282209D01*
X167028Y281899D01*
Y281589D01*
X167105Y281279D01*
X167297Y280969D01*
X167527Y280763D01*
X167795Y280711D01*
X168063Y280814D01*
X168332Y281124D01*
G01X171470Y280711D02*
Y282778D01*
G01Y282416D02*
X171317Y282623D01*
X171087Y282726D01*
X170818Y282778D01*
X170550Y282674D01*
X170320Y282468D01*
X170167Y282158D01*
X170090Y281744D01*
X170167Y281331D01*
X170320Y281021D01*
X170550Y280814D01*
X170818Y280711D01*
X171087Y280763D01*
X171317Y280918D01*
X171470Y281124D01*
G01X173343Y280711D02*
Y282778D01*
G01Y282364D02*
X173535Y282571D01*
X173727Y282726D01*
X173995Y282778D01*
X174187Y282726D01*
X174417Y282571D01*
G01X176980Y283811D02*
Y280711D01*
G01X176443Y282778D02*
X177517D01*
G01X182490Y280711D02*
Y283811D01*
G01Y282261D02*
X182682Y282571D01*
X182912Y282726D01*
X183142Y282778D01*
X183487Y282674D01*
X183717Y282468D01*
X183870Y282106D01*
Y281693D01*
X183793Y281279D01*
X183640Y280969D01*
X183372Y280763D01*
X183142Y280711D01*
X182912Y280763D01*
X182682Y280918D01*
X182490Y281176D01*
G01X185705Y282106D02*
X186932D01*
X186817Y282468D01*
X186625Y282674D01*
X186357Y282778D01*
X186088Y282726D01*
X185858Y282571D01*
X185705Y282209D01*
X185628Y281899D01*
Y281589D01*
X185705Y281279D01*
X185897Y280969D01*
X186127Y280763D01*
X186395Y280711D01*
X186663Y280814D01*
X186932Y281124D01*
G01X190070Y280711D02*
Y282778D01*
G01Y282416D02*
X189917Y282623D01*
X189687Y282726D01*
X189418Y282778D01*
X189150Y282674D01*
X188920Y282468D01*
X188767Y282158D01*
X188690Y281744D01*
X188767Y281331D01*
X188920Y281021D01*
X189150Y280814D01*
X189418Y280711D01*
X189687Y280763D01*
X189917Y280918D01*
X190070Y281124D01*
G01X192480Y283811D02*
Y280711D01*
G01X191943Y282778D02*
X193017D01*
G01X153600Y284200D02*
Y278500D01*
G01Y284200D02*
X162400D01*
G01X153600Y278500D02*
X155200Y277500D01*
X153600Y276500D01*
G01X153700Y302600D02*
X159900D01*
Y299400D01*
X153700D01*
Y302600D01*
G01Y298600D02*
X159900D01*
Y295400D01*
X153700D01*
Y298600D01*
G01X153400Y287900D02*
Y294100D01*
X155559D01*
G01X155279Y287900D02*
X153400D01*
G01X156600Y292626D02*
Y289266D01*
G01X153700Y306700D02*
X159900D01*
Y303500D01*
X153700D01*
Y306700D01*
G01X163600Y315900D02*
Y322100D01*
X166800D01*
Y315900D01*
X163600D01*
G01X159899Y311960D02*
X153699D01*
Y315160D01*
X159899D01*
Y311960D01*
G01X159900Y308100D02*
X153700D01*
Y311300D01*
X159900D01*
Y308100D01*
G01X166626Y348296D02*
Y342096D01*
X163426D01*
Y348296D01*
X166626D01*
G01X159426Y342096D02*
Y348296D01*
X162626D01*
Y342096D01*
X159426D01*
G01X167299Y339980D02*
X165299D01*
G01X160899D02*
X155699D01*
G01X162600Y348900D02*
X156400D01*
Y352100D01*
X162600D01*
Y348900D01*
G01X159200Y434100D02*
Y427900D01*
X156000D01*
Y434100D01*
X159200D01*
G01X163050D02*
Y427900D01*
X159850D01*
Y434100D01*
X163050D01*
G01X163799Y430964D02*
X167699D01*
G01X172382Y437895D02*
X172229Y437740D01*
X172114Y437481D01*
X172037Y437120D01*
X172114Y436810D01*
X172267Y436603D01*
X172536Y436448D01*
X173571D01*
Y439548D01*
X172306D01*
X172037Y439341D01*
X171884Y439031D01*
X171807Y438670D01*
X171884Y438308D01*
X172114Y437998D01*
X172382Y437895D01*
X173571D01*
G01X170317Y436965D02*
X170087Y436655D01*
X169819Y436500D01*
X169512Y436448D01*
X169129Y436551D01*
X168861Y436810D01*
X168784Y437120D01*
X168822Y437430D01*
X168976Y437688D01*
X169742Y438205D01*
X170087Y438566D01*
X170317Y439083D01*
X170394Y439548D01*
X168784D01*
G01X167141Y439186D02*
X166872Y439445D01*
X166566Y439548D01*
X166259Y439445D01*
X165991Y439135D01*
X165799Y438670D01*
X165722Y438205D01*
Y437636D01*
X165799Y437171D01*
X165991Y436758D01*
X166221Y436551D01*
X166489Y436448D01*
X166796Y436551D01*
X167026Y436758D01*
X167179Y437068D01*
X167256Y437481D01*
X167179Y437843D01*
X166987Y438205D01*
X166757Y438411D01*
X166489Y438463D01*
X166182Y438360D01*
X165952Y438101D01*
X165722Y437636D01*
G01X173993Y-676936D02*
Y-668936D01*
G01X177793D02*
X173993Y-673870D01*
G01X178393Y-676936D02*
X175693Y-671603D01*
G01X185993Y-676936D02*
Y-671603D01*
G01Y-672536D02*
X185593Y-672003D01*
X184993Y-671736D01*
X184293Y-671603D01*
X183593Y-671869D01*
X182993Y-672403D01*
X182593Y-673203D01*
X182393Y-674269D01*
X182593Y-675336D01*
X182993Y-676136D01*
X183593Y-676669D01*
X184293Y-676936D01*
X184993Y-676803D01*
X185593Y-676403D01*
X185993Y-675870D01*
G01X192193Y-671603D02*
Y-676936D01*
G01Y-669469D02*
X191993Y-669336D01*
Y-669069D01*
X192193Y-668936D01*
X192393Y-669069D01*
Y-669336D01*
X192193Y-669469D01*
G01X172950Y68557D02*
X175172D01*
X175637Y68710D01*
X175947Y69017D01*
X176050Y69400D01*
X175947Y69783D01*
X175637Y70090D01*
X175172Y70243D01*
X172950D01*
G01X173467Y71772D02*
X173157Y72002D01*
X173002Y72270D01*
X172950Y72577D01*
X173053Y72960D01*
X173312Y73228D01*
X173622Y73305D01*
X173932Y73267D01*
X174190Y73113D01*
X174707Y72347D01*
X175068Y72002D01*
X175585Y71772D01*
X176050Y71695D01*
Y73305D01*
G01Y75523D02*
X175378Y75600D01*
X174810Y75715D01*
X174293Y75868D01*
X173725Y76060D01*
X172950Y76367D01*
Y74833D01*
G01X171100Y68484D02*
X171788D01*
Y74716D01*
X171100D01*
G01X197331Y51427D02*
Y63386D01*
X181919D01*
G01X187600Y86400D02*
X181400D01*
Y89600D01*
X187600D01*
Y86400D01*
G01X174697Y90330D02*
Y84130D01*
G01X171497D02*
Y90330D01*
G01X170697D02*
Y84130D01*
G01X167497D02*
Y90330D01*
G01X187600Y90400D02*
X181400D01*
Y93600D01*
X187600D01*
Y90400D01*
G01X174485Y93244D02*
Y81244D01*
X173099D01*
G01X169409D02*
X167685D01*
Y93244D01*
X169589D01*
G01X181400Y97600D02*
X187600D01*
Y94400D01*
X181400D01*
Y97600D01*
G01X176400Y102700D02*
Y108900D01*
X179600D01*
Y102700D01*
X176400D01*
G01X172759Y93244D02*
X174485D01*
G01X185400Y124600D02*
Y118400D01*
X182200D01*
Y124600D01*
X185400D01*
G01X171032Y118426D02*
Y124626D01*
X174232D01*
Y118426D01*
X171032D01*
G01X176586Y118126D02*
Y124326D01*
X179786D01*
Y118126D01*
X176586D01*
G01X169264Y114254D02*
Y112032D01*
X169417Y111567D01*
X169724Y111257D01*
X170107Y111154D01*
X170490Y111257D01*
X170797Y111567D01*
X170950Y112032D01*
Y114254D01*
G01X172479Y113737D02*
X172709Y114047D01*
X172977Y114202D01*
X173284Y114254D01*
X173667Y114151D01*
X173935Y113892D01*
X174012Y113582D01*
X173974Y113272D01*
X173820Y113014D01*
X173054Y112497D01*
X172709Y112136D01*
X172479Y111619D01*
X172402Y111154D01*
X174012D01*
G01X176307D02*
X176575Y111206D01*
X176882Y111361D01*
X177074Y111619D01*
X177150Y111981D01*
X177074Y112342D01*
X176844Y112652D01*
X176499Y112807D01*
X176115D01*
X175885Y112911D01*
X175694Y113169D01*
X175617Y113531D01*
X175732Y113892D01*
X176000Y114151D01*
X176307Y114254D01*
X176614Y114151D01*
X176882Y113892D01*
X176997Y113531D01*
X176920Y113169D01*
X176729Y112911D01*
X176499Y112807D01*
X176115D01*
X175770Y112652D01*
X175540Y112342D01*
X175464Y111981D01*
X175540Y111619D01*
X175732Y111361D01*
X176039Y111206D01*
X176307Y111154D01*
G01X173500Y139500D02*
Y133300D01*
X170300D01*
Y139500D01*
X173500D01*
G01X178400Y133200D02*
Y139400D01*
X181600D01*
Y133200D01*
X178400D01*
G01X174400D02*
Y139400D01*
X177600D01*
Y133200D01*
X174400D01*
G01X179800Y141029D02*
X180279D01*
G01X238959Y152840D02*
X174587D01*
Y235910D01*
X257657D01*
Y184500D01*
G01X185013Y254811D02*
Y248611D01*
X181813D01*
Y254811D01*
X185013D01*
G01X179013Y254111D02*
Y247911D01*
X175813D01*
Y254111D01*
X179013D01*
G01X176574Y256421D02*
Y262621D01*
X179774D01*
Y256421D01*
X176574D01*
G01X175592Y262061D02*
Y255861D01*
X172392D01*
Y262061D01*
X175592D01*
G01X171567D02*
Y255861D01*
X168367D01*
Y262061D01*
X171567D01*
G01X181750Y257680D02*
Y263880D01*
X184950D01*
Y257680D01*
X181750D01*
G01X176000Y271200D02*
X169800D01*
Y274400D01*
X176000D01*
Y271200D01*
G01X176300Y274400D02*
X182500D01*
Y271200D01*
X176300D01*
Y274400D01*
G01X182750Y265587D02*
Y268013D01*
G01X181000Y269000D02*
X179200D01*
G01X181000Y264600D02*
X179200D01*
G01X181000Y269000D02*
Y264600D01*
G01X180400D02*
Y269000D01*
G01X179800D02*
Y264600D01*
G01X168800Y269000D02*
X179200D01*
Y264600D01*
X168800D01*
Y269000D01*
G01X181800Y301800D02*
X188000D01*
Y298600D01*
X181800D01*
Y301800D01*
G01Y305800D02*
X188000D01*
Y302600D01*
X181800D01*
Y305800D01*
G01X174400Y326800D02*
X180600D01*
Y323600D01*
X174400D01*
Y326800D01*
G01Y330800D02*
X180600D01*
Y327600D01*
X174400D01*
Y330800D01*
G01X167426Y342096D02*
Y348296D01*
X170626D01*
Y342096D01*
X167426D01*
G01X171426D02*
Y348296D01*
X174626D01*
Y342096D01*
X171426D01*
G01X185630Y339980D02*
X176699D01*
G01X172199D02*
X170199D01*
G01X173262Y353472D02*
X173530Y353524D01*
X173837Y353679D01*
X174029Y353937D01*
X174105Y354299D01*
X174029Y354660D01*
X173799Y354970D01*
X173454Y355125D01*
X173070D01*
X172840Y355229D01*
X172649Y355487D01*
X172572Y355849D01*
X172687Y356210D01*
X172955Y356469D01*
X173262Y356572D01*
X173569Y356469D01*
X173837Y356210D01*
X173952Y355849D01*
X173875Y355487D01*
X173684Y355229D01*
X173454Y355125D01*
X173070D01*
X172725Y354970D01*
X172495Y354660D01*
X172419Y354299D01*
X172495Y353937D01*
X172687Y353679D01*
X172994Y353524D01*
X173262Y353472D01*
G01X172410Y414034D02*
X172679Y413775D01*
X172985Y413672D01*
X173292Y413775D01*
X173560Y414085D01*
X173752Y414550D01*
X173829Y415015D01*
Y415584D01*
X173752Y416049D01*
X173560Y416462D01*
X173330Y416669D01*
X173062Y416772D01*
X172755Y416669D01*
X172525Y416462D01*
X172372Y416152D01*
X172295Y415739D01*
X172372Y415377D01*
X172564Y415015D01*
X172794Y414809D01*
X173062Y414757D01*
X173369Y414860D01*
X173599Y415119D01*
X173829Y415584D01*
G01X172900Y434200D02*
X179100D01*
Y431000D01*
X172900D01*
Y434200D01*
G01X172876Y428296D02*
Y422096D01*
X169676D01*
Y428296D01*
X172876D01*
G01X183000Y434300D02*
Y428100D01*
X179800D01*
Y434300D01*
X183000D01*
G01X176700Y428000D02*
Y421800D01*
X173500D01*
Y428000D01*
X176700D01*
G01X171799Y430964D02*
X177499D01*
G01X171000Y434645D02*
X228500D01*
G01X185672Y77353D02*
Y83553D01*
X188872D01*
Y77353D01*
X185672D01*
G01X189712D02*
Y83553D01*
X192912D01*
Y77353D01*
X189712D01*
G01X211700Y74700D02*
Y67300D01*
X194300D01*
Y74700D01*
X211700D01*
G01Y83700D02*
Y76300D01*
X194300D01*
Y83700D01*
X211700D01*
G01X201540Y88726D02*
X204042Y86224D01*
X208386D01*
Y98428D01*
X194694D01*
Y86224D01*
X199038D01*
X201540Y88726D01*
G01X194057Y102450D02*
Y100228D01*
X194210Y99763D01*
X194517Y99453D01*
X194900Y99350D01*
X195283Y99453D01*
X195590Y99763D01*
X195743Y100228D01*
Y102450D01*
G01X198000Y99350D02*
Y102450D01*
X197540Y101830D01*
G01Y99350D02*
X198460D01*
G01X201100Y102450D02*
X200793Y102347D01*
X200563Y102088D01*
X200410Y101778D01*
X200295Y101365D01*
X200257Y100900D01*
X200295Y100435D01*
X200410Y100022D01*
X200563Y99712D01*
X200793Y99453D01*
X201100Y99350D01*
X201407Y99453D01*
X201637Y99712D01*
X201790Y100022D01*
X201905Y100435D01*
X201943Y100900D01*
X201905Y101365D01*
X201790Y101778D01*
X201637Y102088D01*
X201407Y102347D01*
X201100Y102450D01*
G01X190700Y112900D02*
X196900D01*
Y109700D01*
X190700D01*
Y112900D01*
G01X194465Y118426D02*
Y124626D01*
X197665D01*
Y118426D01*
X194465D01*
G01X189800D02*
Y124626D01*
X193000D01*
Y118426D01*
X189800D01*
G01X197583Y139469D02*
Y133269D01*
X194383D01*
Y139469D01*
X197583D01*
G01X182400Y133300D02*
Y139500D01*
X185600D01*
Y133300D01*
X182400D01*
G01X189600Y139500D02*
Y133300D01*
X186400D01*
Y139500D01*
X189600D01*
G01X193600D02*
Y133300D01*
X190400D01*
Y139500D01*
X193600D01*
G01X193700Y141029D02*
X213000D01*
G01X188399D02*
X190100D01*
G01X182883D02*
X183200D01*
G01X193138Y254936D02*
Y248736D01*
X189938D01*
Y254936D01*
X193138D01*
G01X192470Y262430D02*
X198670D01*
Y259230D01*
X192470D01*
Y262430D01*
G01X191600Y265400D02*
X185400D01*
Y268600D01*
X191600D01*
Y265400D01*
G01X189150Y264340D02*
Y258140D01*
X185950D01*
Y264340D01*
X189150D01*
G01X195000Y270300D02*
X201200D01*
Y267100D01*
X195000D01*
Y270300D01*
G01X198600Y263210D02*
X192400D01*
Y266410D01*
X198600D01*
Y263210D01*
G01X189200Y292900D02*
X183000D01*
Y296100D01*
X189200D01*
Y292900D01*
G01X186400Y316300D02*
Y322500D01*
X189600D01*
Y316300D01*
X186400D01*
G01X193800Y309500D02*
X187600D01*
Y312700D01*
X193800D01*
Y309500D01*
G01X191857Y321400D02*
Y319178D01*
X192010Y318713D01*
X192317Y318403D01*
X192700Y318300D01*
X193083Y318403D01*
X193390Y318713D01*
X193543Y319178D01*
Y321400D01*
G01X194957Y318765D02*
X195187Y318507D01*
X195455Y318352D01*
X195800Y318300D01*
X196145Y318403D01*
X196413Y318610D01*
X196605Y318972D01*
X196643Y319385D01*
X196567Y319798D01*
X196375Y320057D01*
X196107Y320263D01*
X195838Y320315D01*
X195570Y320263D01*
X195225Y320057D01*
X195340Y321400D01*
X196375D01*
G01X198057Y318765D02*
X198287Y318507D01*
X198555Y318352D01*
X198900Y318300D01*
X199245Y318403D01*
X199513Y318610D01*
X199705Y318972D01*
X199743Y319385D01*
X199667Y319798D01*
X199475Y320057D01*
X199207Y320263D01*
X198938Y320315D01*
X198670Y320263D01*
X198325Y320057D01*
X198440Y321400D01*
X199475D01*
G01X189083Y331720D02*
X189275Y331410D01*
X189505Y331203D01*
X189773Y331100D01*
X190080Y331203D01*
X190310Y331410D01*
X190540Y331720D01*
X190617Y332133D01*
Y334200D01*
G01X192950Y331100D02*
Y334200D01*
X192490Y333580D01*
G01Y331100D02*
X193410D01*
G01X192150Y359150D02*
Y365350D01*
X195350D01*
Y359150D01*
X192150D01*
G01X185630Y412815D02*
Y358129D01*
G01Y429199D02*
Y349999D01*
G01X195350Y372850D02*
Y366650D01*
X192150D01*
Y372850D01*
X195350D01*
G01X192150Y374900D02*
Y381100D01*
X195350D01*
Y374900D01*
X192150D01*
G01X197095Y390054D02*
X210095D01*
Y375054D01*
X197095D01*
Y390054D01*
G01X192150Y383900D02*
Y390100D01*
X195350D01*
Y383900D01*
X192150D01*
G01X189897Y403957D02*
X189742Y404110D01*
X189483Y404225D01*
X189122Y404302D01*
X188812Y404225D01*
X188605Y404072D01*
X188450Y403803D01*
Y402768D01*
X191550D01*
Y404033D01*
X191343Y404302D01*
X191033Y404455D01*
X190672Y404532D01*
X190310Y404455D01*
X190000Y404225D01*
X189897Y403957D01*
Y402768D01*
G01X188450Y406290D02*
Y407210D01*
G01Y406750D02*
X191550D01*
G01Y406290D02*
Y407210D01*
G01Y409850D02*
X191498Y409543D01*
X191292Y409275D01*
X190982Y409045D01*
X190620Y408892D01*
X190207Y408815D01*
X189793D01*
X189380Y408892D01*
X189018Y409045D01*
X188708Y409275D01*
X188502Y409543D01*
X188450Y409850D01*
X188502Y410157D01*
X188708Y410425D01*
X189018Y410655D01*
X189380Y410808D01*
X189793Y410885D01*
X190207D01*
X190620Y410808D01*
X190982Y410655D01*
X191292Y410425D01*
X191498Y410157D01*
X191550Y409850D01*
G01X191137Y412145D02*
X191395Y412452D01*
X191550Y412797D01*
Y413103D01*
X191395Y413410D01*
X191137Y413640D01*
X190775Y413755D01*
X190413Y413678D01*
X190103Y413487D01*
X189897Y413142D01*
X189793Y412682D01*
X189587Y412413D01*
X189225Y412298D01*
X188863Y412375D01*
X188605Y412567D01*
X188450Y412835D01*
Y413103D01*
X188553Y413372D01*
X188812Y413602D01*
G01X191550Y418383D02*
X188450D01*
Y419342D01*
X188605Y419648D01*
X188812Y419840D01*
X189225Y419917D01*
X189638Y419840D01*
X189897Y419610D01*
X190052Y419342D01*
Y418383D01*
G01Y419342D02*
X191550Y419917D01*
G01Y422250D02*
X191498Y421943D01*
X191292Y421675D01*
X190982Y421445D01*
X190620Y421292D01*
X190207Y421215D01*
X189793D01*
X189380Y421292D01*
X189018Y421445D01*
X188708Y421675D01*
X188502Y421943D01*
X188450Y422250D01*
X188502Y422557D01*
X188708Y422825D01*
X189018Y423055D01*
X189380Y423208D01*
X189793Y423285D01*
X190207D01*
X190620Y423208D01*
X190982Y423055D01*
X191292Y422825D01*
X191498Y422557D01*
X191550Y422250D01*
G01Y424353D02*
X188450D01*
X191033Y425350D01*
X188450Y426347D01*
X191550D01*
G01X190600Y393107D02*
X192822D01*
X193287Y393260D01*
X193597Y393567D01*
X193700Y393950D01*
X193597Y394333D01*
X193287Y394640D01*
X192822Y394793D01*
X190600D01*
G01X193700Y397050D02*
X190600D01*
X191220Y396590D01*
G01X193700D02*
Y397510D01*
G01Y400073D02*
X193028Y400150D01*
X192460Y400265D01*
X191943Y400418D01*
X191375Y400610D01*
X190600Y400917D01*
Y399383D01*
G01X195929Y405132D02*
X196239Y405324D01*
X196446Y405554D01*
X196549Y405822D01*
X196446Y406129D01*
X196239Y406359D01*
X195929Y406589D01*
X195516Y406666D01*
X193449D01*
G01X196549Y409459D02*
X193449D01*
X195671Y408041D01*
Y409957D01*
G01X193449Y412099D02*
X193552Y411792D01*
X193811Y411562D01*
X194121Y411409D01*
X194534Y411294D01*
X194999Y411256D01*
X195464Y411294D01*
X195877Y411409D01*
X196187Y411562D01*
X196446Y411792D01*
X196549Y412099D01*
X196446Y412406D01*
X196187Y412636D01*
X195877Y412789D01*
X195464Y412904D01*
X194999Y412942D01*
X194534Y412904D01*
X194121Y412789D01*
X193811Y412636D01*
X193552Y412406D01*
X193449Y412099D01*
G01X190734Y427652D02*
Y433852D01*
X193934D01*
Y427652D01*
X190734D01*
G01X190782Y437895D02*
X190629Y437740D01*
X190514Y437481D01*
X190437Y437120D01*
X190514Y436810D01*
X190667Y436603D01*
X190936Y436448D01*
X191971D01*
Y439548D01*
X190706D01*
X190437Y439341D01*
X190284Y439031D01*
X190207Y438670D01*
X190284Y438308D01*
X190514Y437998D01*
X190782Y437895D01*
X191971D01*
G01X188717Y436965D02*
X188487Y436655D01*
X188219Y436500D01*
X187912Y436448D01*
X187529Y436551D01*
X187261Y436810D01*
X187184Y437120D01*
X187222Y437430D01*
X187376Y437688D01*
X188142Y438205D01*
X188487Y438566D01*
X188717Y439083D01*
X188794Y439548D01*
X187184D01*
G01X184889D02*
X184621Y439496D01*
X184314Y439341D01*
X184122Y439083D01*
X184046Y438721D01*
X184122Y438360D01*
X184352Y438050D01*
X184697Y437895D01*
X185081D01*
X185311Y437791D01*
X185502Y437533D01*
X185579Y437171D01*
X185464Y436810D01*
X185196Y436551D01*
X184889Y436448D01*
X184582Y436551D01*
X184314Y436810D01*
X184199Y437171D01*
X184276Y437533D01*
X184467Y437791D01*
X184697Y437895D01*
X185081D01*
X185426Y438050D01*
X185656Y438360D01*
X185732Y438721D01*
X185656Y439083D01*
X185464Y439341D01*
X185157Y439496D01*
X184889Y439548D01*
G01X206890Y32638D02*
X225394D01*
Y9016D01*
X222048D01*
Y4292D01*
G02X216142Y-1614I-5906J0D01*
G02X210236Y4292I0J5906D01*
G01Y9016D01*
X206890D01*
Y32638D01*
G01X204939Y10574D02*
X205197Y10881D01*
X205352Y11226D01*
Y11532D01*
X205197Y11839D01*
X204939Y12069D01*
X204577Y12184D01*
X204215Y12107D01*
X203905Y11916D01*
X203699Y11571D01*
X203595Y11111D01*
X203389Y10842D01*
X203027Y10727D01*
X202665Y10804D01*
X202407Y10996D01*
X202252Y11264D01*
Y11532D01*
X202355Y11801D01*
X202614Y12031D01*
G01X202510Y15322D02*
X202355Y15092D01*
X202252Y14824D01*
Y14517D01*
X202407Y14172D01*
X202665Y13904D01*
X202975Y13712D01*
X203492Y13559D01*
X203957Y13521D01*
X204422Y13597D01*
X204732Y13712D01*
X205042Y13942D01*
X205249Y14211D01*
X205352Y14479D01*
Y14747D01*
X205249Y15016D01*
X205094Y15246D01*
X204887Y15437D01*
G01X205352Y16582D02*
X202252D01*
X204835Y17579D01*
X202252Y18576D01*
X205352D01*
G01X206385Y19529D02*
Y21829D01*
G01X202252Y22821D02*
X205352Y23779D01*
X202252Y24737D01*
G01Y26419D02*
Y27339D01*
G01Y26879D02*
X205352D01*
G01Y26419D02*
Y27339D01*
G01Y29097D02*
X202252D01*
X205352Y30861D01*
X202252D01*
G01X206949Y34031D02*
Y37131D01*
X207715D01*
X208022Y36976D01*
X208252Y36769D01*
X208444Y36459D01*
X208597Y36098D01*
X208635Y35581D01*
X208597Y35064D01*
X208444Y34703D01*
X208252Y34393D01*
X208022Y34186D01*
X207715Y34031D01*
X206949D01*
G01X210164Y36614D02*
X210394Y36924D01*
X210662Y37079D01*
X210969Y37131D01*
X211352Y37028D01*
X211620Y36769D01*
X211697Y36459D01*
X211659Y36149D01*
X211505Y35891D01*
X210739Y35374D01*
X210394Y35013D01*
X210164Y34496D01*
X210087Y34031D01*
X211697D01*
G01X213992D02*
Y37131D01*
X213532Y36511D01*
G01Y34031D02*
X214452D01*
G01X209400Y39400D02*
Y45600D01*
X212600D01*
Y39400D01*
X209400D01*
G01X212378Y113444D02*
Y107244D01*
X209178D01*
Y113444D01*
X212378D01*
G01X198400Y118400D02*
Y124600D01*
X201600D01*
Y118400D01*
X198400D01*
G01X208589Y118426D02*
Y124626D01*
X211789D01*
Y118426D01*
X208589D01*
G01X202400Y118400D02*
Y124600D01*
X205600D01*
Y118400D01*
X202400D01*
G01X214357Y139469D02*
Y133269D01*
X211157D01*
Y139469D01*
X214357D01*
G01X198385Y133269D02*
Y139469D01*
X201585D01*
Y133269D01*
X198385D01*
G01X210227Y139469D02*
Y133269D01*
X207027D01*
Y139469D01*
X210227D01*
G01X202520Y133269D02*
Y139469D01*
X205720D01*
Y133269D01*
X202520D01*
G01X212240Y243300D02*
X206040D01*
Y246500D01*
X212240D01*
Y243300D01*
G01X206312Y248524D02*
Y254724D01*
X209512D01*
Y248524D01*
X206312D01*
G01X205663Y254886D02*
Y248686D01*
X202463D01*
Y254886D01*
X205663D01*
G01X198210Y248686D02*
Y254886D01*
X201410D01*
Y248686D01*
X198210D01*
G01X207900Y271400D02*
Y277600D01*
X211100D01*
Y271400D01*
X207900D01*
G01X200900Y274600D02*
X207100D01*
Y271400D01*
X200900D01*
Y274600D01*
G01X200207Y293500D02*
Y291278D01*
X200360Y290813D01*
X200667Y290503D01*
X201050Y290400D01*
X201433Y290503D01*
X201740Y290813D01*
X201893Y291278D01*
Y293500D01*
G01X203307Y290865D02*
X203537Y290607D01*
X203805Y290452D01*
X204150Y290400D01*
X204495Y290503D01*
X204763Y290710D01*
X204955Y291072D01*
X204993Y291485D01*
X204917Y291898D01*
X204725Y292157D01*
X204457Y292363D01*
X204188Y292415D01*
X203920Y292363D01*
X203575Y292157D01*
X203690Y293500D01*
X204725D01*
G01X207710Y290400D02*
Y293500D01*
X206292Y291278D01*
X208208D01*
G01X204000Y298100D02*
X207002Y294498D01*
X208752D01*
Y306702D01*
X199248D01*
Y294498D01*
X200998D01*
X204000Y298100D01*
G01X208000Y309200D02*
X213700D01*
G01X200300D02*
X206000D01*
G01X200300D02*
Y318000D01*
G01X206000Y309200D02*
X207000Y310800D01*
X208000Y309200D01*
G01X200300Y318000D02*
X213700D01*
G01X207921Y330750D02*
Y345650D01*
G01X198079Y335650D02*
Y323003D01*
X207921D01*
Y325650D01*
G01Y350750D02*
Y353397D01*
X198079D01*
Y340750D01*
G01X197250Y373000D02*
X210250D01*
Y358000D01*
X197250D01*
Y373000D01*
G01X211900Y374900D02*
Y381100D01*
X215100D01*
Y374900D01*
X211900D01*
G01X215100Y390600D02*
Y384400D01*
X211900D01*
Y390600D01*
X215100D01*
G01X198904Y393905D02*
X198597Y393957D01*
X198329Y394163D01*
X198099Y394473D01*
X197946Y394835D01*
X197869Y395248D01*
Y395662D01*
X197946Y396075D01*
X198099Y396437D01*
X198329Y396747D01*
X198597Y396953D01*
X198904Y397005D01*
X199211Y396953D01*
X199479Y396747D01*
X199709Y396437D01*
X199862Y396075D01*
X199939Y395662D01*
Y395248D01*
X199862Y394835D01*
X199709Y394473D01*
X199479Y394163D01*
X199211Y393957D01*
X198904Y393905D01*
G01X199211Y394732D02*
X199671Y393905D01*
G01X202004D02*
Y397005D01*
X201544Y396385D01*
G01Y393905D02*
X202464D01*
G01X211400Y418000D02*
X205200D01*
Y421200D01*
X211400D01*
Y418000D01*
G01X197805Y427652D02*
Y433852D01*
X201005D01*
Y427652D01*
X197805D01*
G01X201800Y427600D02*
Y433800D01*
X205000D01*
Y427600D01*
X201800D01*
G01X213300Y433800D02*
Y427600D01*
X210100D01*
Y433800D01*
X213300D01*
G01X208900D02*
Y427600D01*
X205700D01*
Y433800D01*
X208900D01*
G01X217400Y39400D02*
Y45600D01*
X220600D01*
Y39400D01*
X217400D01*
G01X216600Y45600D02*
Y39400D01*
X213400D01*
Y45600D01*
X216600D01*
G01X216800Y84600D02*
X223400D01*
G01Y78100D02*
X216800D01*
Y91100D01*
X223400D01*
Y78100D01*
G01X212900Y89400D02*
Y95600D01*
X216100D01*
Y89400D01*
X212900D01*
G01X221157Y96753D02*
X221310Y96908D01*
X221425Y97167D01*
X221502Y97528D01*
X221425Y97838D01*
X221272Y98045D01*
X221003Y98200D01*
X219968D01*
Y95100D01*
X221233D01*
X221502Y95307D01*
X221655Y95617D01*
X221732Y95978D01*
X221655Y96340D01*
X221425Y96650D01*
X221157Y96753D01*
X219968D01*
G01X222953Y95100D02*
Y98200D01*
X223950Y95617D01*
X224947Y98200D01*
Y95100D01*
G01X227893Y97942D02*
X227663Y98097D01*
X227395Y98200D01*
X227088D01*
X226743Y98045D01*
X226475Y97787D01*
X226283Y97477D01*
X226130Y96960D01*
X226092Y96495D01*
X226168Y96030D01*
X226283Y95720D01*
X226513Y95410D01*
X226782Y95203D01*
X227050Y95100D01*
X227318D01*
X227587Y95203D01*
X227817Y95358D01*
X228008Y95565D01*
G01X229000Y94067D02*
X231300D01*
G01X232522Y97683D02*
X232752Y97993D01*
X233020Y98148D01*
X233327Y98200D01*
X233710Y98097D01*
X233978Y97838D01*
X234055Y97528D01*
X234017Y97218D01*
X233863Y96960D01*
X233097Y96443D01*
X232752Y96082D01*
X232522Y95565D01*
X232445Y95100D01*
X234055D01*
G01X235507Y95565D02*
X235737Y95307D01*
X236005Y95152D01*
X236350Y95100D01*
X236695Y95203D01*
X236963Y95410D01*
X237155Y95772D01*
X237193Y96185D01*
X237117Y96598D01*
X236925Y96857D01*
X236657Y97063D01*
X236388Y97115D01*
X236120Y97063D01*
X235775Y96857D01*
X235890Y98200D01*
X236925D01*
G01X238453Y95100D02*
Y98200D01*
X239450Y95617D01*
X240447Y98200D01*
Y95100D01*
G01X241745D02*
Y98200D01*
G01X243355D02*
Y95100D01*
G01Y96650D02*
X241745D01*
G01X245075Y97167D02*
X246225D01*
X245075Y95100D01*
X246225D01*
G01X217764Y104984D02*
X231632D01*
Y115984D01*
X217764D01*
Y104984D01*
G01X219020Y100414D02*
X212820D01*
Y103614D01*
X219020D01*
Y100414D01*
G01X212820Y99584D02*
X219020D01*
Y96384D01*
X212820D01*
Y99584D01*
G01X216385Y113442D02*
Y107242D01*
X213185D01*
Y113442D01*
X216385D01*
G01X221700Y118400D02*
Y124600D01*
X224900D01*
Y118400D01*
X221700D01*
G01X212864Y118426D02*
Y124626D01*
X216064D01*
Y118426D01*
X212864D01*
G01X222878Y139469D02*
Y133269D01*
X219678D01*
Y139469D01*
X222878D01*
G01X218862D02*
Y133269D01*
X215662D01*
Y139469D01*
X218862D01*
G01X226884D02*
Y133269D01*
X223684D01*
Y139469D01*
X226884D01*
G01X226700Y141029D02*
X230100D01*
G01X216800D02*
X222900D01*
G01X228751Y247721D02*
X223930D01*
G01X216600Y247500D02*
Y253700D01*
X219800D01*
Y247500D01*
X216600D01*
G01X220200D02*
Y253700D01*
X223400D01*
Y247500D01*
X220200D01*
G01X226720Y257330D02*
X220520D01*
Y260530D01*
X226720D01*
Y257330D01*
G01X220700Y277500D02*
Y283700D01*
X223900D01*
Y277500D01*
X220700D01*
G01X227600Y295000D02*
X221400D01*
Y298200D01*
X227600D01*
Y295000D01*
G01Y299000D02*
X221400D01*
Y302200D01*
X227600D01*
Y299000D01*
G01X219660Y308760D02*
Y314960D01*
X222860D01*
Y308760D01*
X219660D01*
G01X221400Y306200D02*
X227600D01*
Y303000D01*
X221400D01*
Y306200D01*
G01X213700Y318000D02*
Y309200D01*
G01X226900Y330400D02*
Y336600D01*
X230100D01*
Y330400D01*
X226900D01*
G01X222200Y329400D02*
Y323200D01*
X219000D01*
Y329400D01*
X222200D01*
G01X219000Y316400D02*
Y322600D01*
X222200D01*
Y316400D01*
X219000D01*
G01X226377Y335258D02*
X221377D01*
Y336778D01*
X221627Y337285D01*
X222210Y337665D01*
X222877Y337792D01*
X223544Y337665D01*
X224044Y337348D01*
X224294Y336778D01*
Y335258D01*
G01X221794Y343018D02*
X221544Y342638D01*
X221377Y342195D01*
Y341688D01*
X221627Y341118D01*
X222044Y340675D01*
X222544Y340358D01*
X223377Y340105D01*
X224127Y340042D01*
X224877Y340168D01*
X225377Y340358D01*
X225877Y340738D01*
X226210Y341182D01*
X226377Y341625D01*
Y342068D01*
X226210Y342512D01*
X225960Y342892D01*
X225627Y343208D01*
G01X226377Y345395D02*
X221377D01*
G01Y348055D02*
X226377D01*
G01X223877D02*
Y345395D01*
G01X221377Y356925D02*
X226377D01*
G01X221377Y355468D02*
Y358382D01*
G01X226377Y360758D02*
X221377D01*
Y362278D01*
X221627Y362785D01*
X222210Y363165D01*
X222877Y363292D01*
X223544Y363165D01*
X224044Y362848D01*
X224294Y362278D01*
Y360758D01*
G01X226377Y365478D02*
X221377D01*
X225544Y367125D01*
X221377Y368772D01*
X226377D01*
G01X226900Y343200D02*
Y349400D01*
X230100D01*
Y343200D01*
X226900D01*
G01X225050Y374710D02*
Y380910D01*
X228250D01*
Y374710D01*
X225050D01*
G01X222040Y374000D02*
X228240D01*
Y370800D01*
X222040D01*
Y374000D01*
G01X224400Y380875D02*
Y374675D01*
X221200D01*
Y380875D01*
X224400D01*
G01X213650Y369200D02*
X213343Y369252D01*
X213075Y369458D01*
X212845Y369768D01*
X212692Y370130D01*
X212615Y370543D01*
Y370957D01*
X212692Y371370D01*
X212845Y371732D01*
X213075Y372042D01*
X213343Y372248D01*
X213650Y372300D01*
X213957Y372248D01*
X214225Y372042D01*
X214455Y371732D01*
X214608Y371370D01*
X214685Y370957D01*
Y370543D01*
X214608Y370130D01*
X214455Y369768D01*
X214225Y369458D01*
X213957Y369252D01*
X213650Y369200D01*
G01X213957Y370027D02*
X214417Y369200D01*
G01X215907Y369820D02*
X216137Y369458D01*
X216443Y369252D01*
X216788Y369200D01*
X217095Y369252D01*
X217402Y369510D01*
X217593Y369820D01*
X217632Y370130D01*
X217555Y370492D01*
X217287Y370750D01*
X217018Y370853D01*
X216673D01*
G01X217018D02*
X217248Y371008D01*
X217440Y371267D01*
X217517Y371577D01*
X217440Y371887D01*
X217248Y372145D01*
X216903Y372300D01*
X216558Y372248D01*
X216213Y372042D01*
G01X222030Y384860D02*
X228230D01*
Y381660D01*
X222030D01*
Y384860D01*
G01X228100Y408400D02*
Y402200D01*
X224900D01*
Y408400D01*
X228100D01*
G01X222500Y414400D02*
X216300D01*
Y417600D01*
X222500D01*
Y414400D01*
G01X221200Y433800D02*
Y427600D01*
X218000D01*
Y433800D01*
X221200D01*
G01X217300D02*
Y427600D01*
X214100D01*
Y433800D01*
X217300D01*
G01X225265Y435383D02*
Y438483D01*
G01X226875D02*
Y435383D01*
G01Y436933D02*
X225265D01*
G01X229630Y435383D02*
Y438483D01*
X228212Y436261D01*
X230128D01*
G01X233465Y32638D02*
X251969D01*
Y9016D01*
X248623D01*
Y4292D01*
G02X242717Y-1614I-5906J0D01*
G02X236811Y4292I0J5906D01*
G01Y9016D01*
X233465D01*
Y32638D01*
G01X231121Y10574D02*
X231379Y10881D01*
X231534Y11226D01*
Y11532D01*
X231379Y11839D01*
X231121Y12069D01*
X230759Y12184D01*
X230397Y12107D01*
X230087Y11916D01*
X229881Y11571D01*
X229777Y11111D01*
X229571Y10842D01*
X229209Y10727D01*
X228847Y10804D01*
X228589Y10996D01*
X228434Y11264D01*
Y11532D01*
X228537Y11801D01*
X228796Y12031D01*
G01X228692Y15322D02*
X228537Y15092D01*
X228434Y14824D01*
Y14517D01*
X228589Y14172D01*
X228847Y13904D01*
X229157Y13712D01*
X229674Y13559D01*
X230139Y13521D01*
X230604Y13597D01*
X230914Y13712D01*
X231224Y13942D01*
X231431Y14211D01*
X231534Y14479D01*
Y14747D01*
X231431Y15016D01*
X231276Y15246D01*
X231069Y15437D01*
G01X231534Y16582D02*
X228434D01*
X231017Y17579D01*
X228434Y18576D01*
X231534D01*
G01X232567Y19529D02*
Y21829D01*
G01X231534Y23012D02*
X228434D01*
Y23932D01*
X228589Y24239D01*
X228951Y24469D01*
X229364Y24546D01*
X229777Y24469D01*
X230087Y24277D01*
X230242Y23932D01*
Y23012D01*
G01X229984Y27109D02*
Y27876D01*
X230914D01*
X231224Y27646D01*
X231431Y27377D01*
X231534Y26994D01*
X231431Y26611D01*
X231224Y26342D01*
X230914Y26112D01*
X230552Y25959D01*
X230139Y25882D01*
X229777D01*
X229467Y25959D01*
X229106Y26112D01*
X228796Y26342D01*
X228589Y26572D01*
X228434Y26879D01*
Y27147D01*
X228537Y27454D01*
X228744Y27684D01*
G01X231534Y29136D02*
X228434D01*
Y29902D01*
X228589Y30209D01*
X228796Y30439D01*
X229106Y30631D01*
X229467Y30784D01*
X229984Y30822D01*
X230501Y30784D01*
X230862Y30631D01*
X231172Y30439D01*
X231379Y30209D01*
X231534Y29902D01*
Y29136D01*
G01X233524Y34031D02*
Y37131D01*
X234290D01*
X234597Y36976D01*
X234827Y36769D01*
X235019Y36459D01*
X235172Y36098D01*
X235210Y35581D01*
X235172Y35064D01*
X235019Y34703D01*
X234827Y34393D01*
X234597Y34186D01*
X234290Y34031D01*
X233524D01*
G01X236739Y36614D02*
X236969Y36924D01*
X237237Y37079D01*
X237544Y37131D01*
X237927Y37028D01*
X238195Y36769D01*
X238272Y36459D01*
X238234Y36149D01*
X238080Y35891D01*
X237314Y35374D01*
X236969Y35013D01*
X236739Y34496D01*
X236662Y34031D01*
X238272D01*
G01X239839Y36614D02*
X240069Y36924D01*
X240337Y37079D01*
X240644Y37131D01*
X241027Y37028D01*
X241295Y36769D01*
X241372Y36459D01*
X241334Y36149D01*
X241180Y35891D01*
X240414Y35374D01*
X240069Y35013D01*
X239839Y34496D01*
X239762Y34031D01*
X241372D01*
G01X235400Y39900D02*
Y46100D01*
X238600D01*
Y39900D01*
X235400D01*
G01X231400Y41061D02*
Y44661D01*
G01X232696Y46100D02*
X234600D01*
Y39900D01*
X232846D01*
G01X231350Y99450D02*
X231043Y99502D01*
X230775Y99708D01*
X230545Y100018D01*
X230392Y100380D01*
X230315Y100793D01*
Y101207D01*
X230392Y101620D01*
X230545Y101982D01*
X230775Y102292D01*
X231043Y102498D01*
X231350Y102550D01*
X231657Y102498D01*
X231925Y102292D01*
X232155Y101982D01*
X232308Y101620D01*
X232385Y101207D01*
Y100793D01*
X232308Y100380D01*
X232155Y100018D01*
X231925Y99708D01*
X231657Y99502D01*
X231350Y99450D01*
G01X233645Y99863D02*
X233952Y99605D01*
X234297Y99450D01*
X234603D01*
X234910Y99605D01*
X235140Y99863D01*
X235255Y100225D01*
X235178Y100587D01*
X234987Y100897D01*
X234642Y101103D01*
X234182Y101207D01*
X233913Y101413D01*
X233798Y101775D01*
X233875Y102137D01*
X234067Y102395D01*
X234335Y102550D01*
X234603D01*
X234872Y102447D01*
X235102Y102188D01*
G01X238393Y102292D02*
X238163Y102447D01*
X237895Y102550D01*
X237588D01*
X237243Y102395D01*
X236975Y102137D01*
X236783Y101827D01*
X236630Y101310D01*
X236592Y100845D01*
X236668Y100380D01*
X236783Y100070D01*
X237013Y99760D01*
X237282Y99553D01*
X237550Y99450D01*
X237818D01*
X238087Y99553D01*
X238317Y99708D01*
X238508Y99915D01*
G01X240650Y99450D02*
Y102550D01*
X240190Y101930D01*
G01Y99450D02*
X241110D01*
G01X236200Y112600D02*
Y106400D01*
X233000D01*
Y112600D01*
X236200D01*
G01X240600Y118400D02*
Y124600D01*
X243800D01*
Y118400D01*
X240600D01*
G01X227000D02*
Y124600D01*
X230200D01*
Y118400D01*
X227000D01*
G01X236782Y118426D02*
Y124626D01*
X239982D01*
Y118426D01*
X236782D01*
G01X231911Y133469D02*
Y139669D01*
X235111D01*
Y133469D01*
X231911D01*
G01X240595Y133269D02*
Y139469D01*
X243795D01*
Y133269D01*
X240595D01*
G01X236055D02*
Y139469D01*
X239255D01*
Y133269D01*
X236055D01*
G01X230996Y139469D02*
Y133269D01*
X227796D01*
Y139469D01*
X230996D01*
G01X240200Y141029D02*
X246760D01*
G01X234825D02*
X238000D01*
G01X269468Y247721D02*
X232270D01*
G01X237500Y249100D02*
Y255300D01*
X240700D01*
Y249100D01*
X237500D01*
G01X233500D02*
Y255300D01*
X236700D01*
Y249100D01*
X233500D01*
G01X228100Y259800D02*
X234300D01*
Y256600D01*
X228100D01*
Y259800D01*
G01X244540Y263066D02*
Y256866D01*
X241340D01*
Y263066D01*
X244540D01*
G01X238904Y315114D02*
X245104D01*
Y311914D01*
X238904D01*
Y315114D01*
G01Y320910D02*
X245104D01*
Y317710D01*
X238904D01*
Y320910D01*
G01X237900Y317800D02*
X231700D01*
Y321000D01*
X237900D01*
Y317800D01*
G01X240100Y336600D02*
Y330400D01*
X236900D01*
Y336600D01*
X240100D01*
G01X244100Y345100D02*
Y338900D01*
X240900D01*
Y345100D01*
X244100D01*
G01X237015Y360149D02*
Y363849D01*
G01X256701Y353173D02*
X237015D01*
Y353449D01*
G01X232423Y363650D02*
X232500Y364322D01*
X232615Y364890D01*
X232768Y365407D01*
X232960Y365975D01*
X233267Y366750D01*
X231733D01*
G01X229550Y384750D02*
Y387850D01*
X229090Y387230D01*
G01Y384750D02*
X230010D01*
G01X232650D02*
Y387850D01*
X232190Y387230D01*
G01Y384750D02*
X233110D01*
G01X237015Y383049D02*
Y386749D01*
G01Y393449D02*
Y393725D01*
X256701D01*
Y393449D01*
G01X244253Y48331D02*
X247600D01*
X249500Y46131D01*
X251400Y48331D01*
X254747D01*
Y39669D01*
X244253D01*
Y48331D01*
G01X256579Y36997D02*
X256886Y36739D01*
X257231Y36584D01*
X257537D01*
X257844Y36739D01*
X258074Y36997D01*
X258189Y37359D01*
X258112Y37721D01*
X257921Y38031D01*
X257576Y38237D01*
X257116Y38341D01*
X256847Y38547D01*
X256732Y38909D01*
X256809Y39271D01*
X257001Y39529D01*
X257269Y39684D01*
X257537D01*
X257806Y39581D01*
X258036Y39322D01*
G01X259334Y39684D02*
X259871Y36584D01*
X260484Y39684D01*
X261097Y36584D01*
X261634Y39684D01*
G01X263584Y36584D02*
X263852Y36636D01*
X264159Y36791D01*
X264351Y37049D01*
X264427Y37411D01*
X264351Y37772D01*
X264121Y38082D01*
X263776Y38237D01*
X263392D01*
X263162Y38341D01*
X262971Y38599D01*
X262894Y38961D01*
X263009Y39322D01*
X263277Y39581D01*
X263584Y39684D01*
X263891Y39581D01*
X264159Y39322D01*
X264274Y38961D01*
X264197Y38599D01*
X264006Y38341D01*
X263776Y38237D01*
X263392D01*
X263047Y38082D01*
X262817Y37772D01*
X262741Y37411D01*
X262817Y37049D01*
X263009Y36791D01*
X263316Y36636D01*
X263584Y36584D01*
G01X245050Y49567D02*
X244743Y49619D01*
X244475Y49825D01*
X244245Y50135D01*
X244092Y50497D01*
X244015Y50910D01*
Y51324D01*
X244092Y51737D01*
X244245Y52099D01*
X244475Y52409D01*
X244743Y52615D01*
X245050Y52667D01*
X245357Y52615D01*
X245625Y52409D01*
X245855Y52099D01*
X246008Y51737D01*
X246085Y51324D01*
Y50910D01*
X246008Y50497D01*
X245855Y50135D01*
X245625Y49825D01*
X245357Y49619D01*
X245050Y49567D01*
G01X245357Y50394D02*
X245817Y49567D01*
G01X248150D02*
Y52667D01*
X247690Y52047D01*
G01Y49567D02*
X248610D01*
G01X250407Y50187D02*
X250637Y49825D01*
X250943Y49619D01*
X251288Y49567D01*
X251595Y49619D01*
X251902Y49877D01*
X252093Y50187D01*
X252132Y50497D01*
X252055Y50859D01*
X251787Y51117D01*
X251518Y51220D01*
X251173D01*
G01X251518D02*
X251748Y51375D01*
X251940Y51634D01*
X252017Y51944D01*
X251940Y52254D01*
X251748Y52512D01*
X251403Y52667D01*
X251058Y52615D01*
X250713Y52409D01*
G01X254579Y66950D02*
Y54303D01*
X264421D01*
Y56950D01*
G01Y82050D02*
Y84697D01*
X254579D01*
Y72050D01*
G01X245300Y110700D02*
Y104500D01*
X242100D01*
Y110700D01*
X245300D01*
G01X258900Y97000D02*
X252700D01*
Y100200D01*
X258900D01*
Y97000D01*
G01Y93500D02*
X252700D01*
Y96700D01*
X258900D01*
Y93500D01*
G01X255932Y117221D02*
Y114566D01*
G01X254580Y112558D02*
X252732D01*
Y118758D01*
X254990D01*
G01X256739Y113851D02*
Y117221D01*
G01X244400Y118400D02*
Y124600D01*
X247600D01*
Y118400D01*
X244400D01*
G01X255100Y108700D02*
X250500D01*
Y111900D01*
X254800D01*
G01X251812Y140387D02*
Y134187D01*
X249880D01*
G01X248612Y135630D02*
Y137770D01*
G01X247805Y137500D02*
Y135630D01*
G01X246370Y134187D02*
X244605D01*
Y140387D01*
X246760D01*
G01X250100Y141029D02*
X254205D01*
G01X250070Y140387D02*
X251812D01*
G01X257657Y152840D02*
X249384D01*
G01X244780D02*
X242996D01*
G01X257728Y254779D02*
Y248579D01*
X254528D01*
Y254779D01*
X257728D01*
G01X252105Y254753D02*
Y248553D01*
X248905D01*
Y254753D01*
X252105D01*
G01X245348Y258965D02*
X251548D01*
Y255765D01*
X245348D01*
Y258965D01*
G01X251108Y265792D02*
Y261192D01*
G01X255608Y265792D02*
Y261192D01*
G01X245608Y265792D02*
Y261192D01*
G01X255608Y261292D02*
Y261192D01*
X245608D01*
G01Y265792D02*
X255608D01*
G01X250108D02*
Y261192D01*
G01X248713Y270003D02*
X254913D01*
Y266803D01*
X248713D01*
Y270003D01*
G01X250800Y275810D02*
Y282010D01*
X254000D01*
Y275810D01*
X250800D01*
G01X245900Y315100D02*
X252100D01*
Y311900D01*
X245900D01*
Y315100D01*
G01Y323600D02*
X252100D01*
Y320400D01*
X245900D01*
Y323600D01*
G01X256701Y361849D02*
Y360149D01*
G01Y353449D02*
Y353173D01*
G01Y386749D02*
Y385049D01*
G01X259500Y428300D02*
Y422100D01*
X256300D01*
Y428300D01*
X259500D01*
G01X252410Y422114D02*
Y428314D01*
X255610D01*
Y422114D01*
X252410D01*
G01X244500Y434645D02*
X259500D01*
G01X251332Y437895D02*
X251179Y437740D01*
X251064Y437481D01*
X250987Y437120D01*
X251064Y436810D01*
X251217Y436603D01*
X251486Y436448D01*
X252521D01*
Y439548D01*
X251256D01*
X250987Y439341D01*
X250834Y439031D01*
X250757Y438670D01*
X250834Y438308D01*
X251064Y437998D01*
X251332Y437895D01*
X252521D01*
G01X248539Y439548D02*
Y436448D01*
X248999Y437068D01*
G01Y439548D02*
X248079D01*
G01X263386Y7048D02*
X271063D01*
Y-4763D01*
X284843D01*
Y7048D01*
X292520D01*
Y7640D01*
G01X259914Y18257D02*
X256814Y19215D01*
X259914Y20173D01*
G01X258829Y19828D02*
Y18602D01*
G01X257072Y23158D02*
X256917Y22928D01*
X256814Y22660D01*
Y22353D01*
X256969Y22008D01*
X257227Y21740D01*
X257537Y21548D01*
X258054Y21395D01*
X258519Y21357D01*
X258984Y21433D01*
X259294Y21548D01*
X259604Y21778D01*
X259811Y22047D01*
X259914Y22315D01*
Y22583D01*
X259811Y22852D01*
X259656Y23082D01*
X259449Y23273D01*
G01X260947Y24265D02*
Y26565D01*
G01X258261Y28822D02*
X258106Y28975D01*
X257847Y29090D01*
X257486Y29167D01*
X257176Y29090D01*
X256969Y28937D01*
X256814Y28668D01*
Y27633D01*
X259914D01*
Y28898D01*
X259707Y29167D01*
X259397Y29320D01*
X259036Y29397D01*
X258674Y29320D01*
X258364Y29090D01*
X258261Y28822D01*
Y27633D01*
G01X256814Y31615D02*
X259914D01*
G01X256814Y30733D02*
Y32497D01*
G01X259914Y33833D02*
X256814D01*
X259914Y35597D01*
X256814D01*
G01X263386Y7640D02*
Y7048D01*
G01Y17040D02*
Y16640D01*
G01X265553Y31063D02*
X263386D01*
Y23040D01*
G01X262100Y49331D02*
X273900D01*
Y40669D01*
X262100D01*
Y49331D01*
G01X266484Y53299D02*
Y51077D01*
X266637Y50612D01*
X266944Y50302D01*
X267327Y50199D01*
X267710Y50302D01*
X268017Y50612D01*
X268170Y51077D01*
Y53299D01*
G01X269584Y50664D02*
X269814Y50406D01*
X270082Y50251D01*
X270427Y50199D01*
X270772Y50302D01*
X271040Y50509D01*
X271232Y50871D01*
X271270Y51284D01*
X271194Y51697D01*
X271002Y51956D01*
X270734Y52162D01*
X270465Y52214D01*
X270197Y52162D01*
X269852Y51956D01*
X269967Y53299D01*
X271002D01*
G01X273450Y50199D02*
X273527Y50871D01*
X273642Y51439D01*
X273795Y51956D01*
X273987Y52524D01*
X274294Y53299D01*
X272760D01*
G01X266383Y64620D02*
X266575Y64310D01*
X266805Y64103D01*
X267073Y64000D01*
X267380Y64103D01*
X267610Y64310D01*
X267840Y64620D01*
X267917Y65033D01*
Y67100D01*
G01X270250Y64000D02*
Y67100D01*
X269790Y66480D01*
G01Y64000D02*
X270710D01*
G01X272507Y64620D02*
X272737Y64258D01*
X273043Y64052D01*
X273388Y64000D01*
X273695Y64052D01*
X274002Y64310D01*
X274193Y64620D01*
X274232Y64930D01*
X274155Y65292D01*
X273887Y65550D01*
X273618Y65653D01*
X273273D01*
G01X273618D02*
X273848Y65808D01*
X274040Y66067D01*
X274117Y66377D01*
X274040Y66687D01*
X273848Y66945D01*
X273503Y67100D01*
X273158Y67048D01*
X272813Y66842D01*
G01X264421Y62050D02*
Y76950D01*
G01X266183Y82600D02*
Y85700D01*
X267103D01*
X267410Y85545D01*
X267640Y85183D01*
X267717Y84770D01*
X267640Y84357D01*
X267448Y84047D01*
X267103Y83892D01*
X266183D01*
G01X269207Y83220D02*
X269437Y82858D01*
X269743Y82652D01*
X270088Y82600D01*
X270395Y82652D01*
X270702Y82910D01*
X270893Y83220D01*
X270932Y83530D01*
X270855Y83892D01*
X270587Y84150D01*
X270318Y84253D01*
X269973D01*
G01X270318D02*
X270548Y84408D01*
X270740Y84667D01*
X270817Y84977D01*
X270740Y85287D01*
X270548Y85545D01*
X270203Y85700D01*
X269858Y85648D01*
X269513Y85442D01*
G01X272192Y85700D02*
X273150Y82600D01*
X274108Y85700D01*
G01X275407Y83220D02*
X275637Y82858D01*
X275943Y82652D01*
X276288Y82600D01*
X276595Y82652D01*
X276902Y82910D01*
X277093Y83220D01*
X277132Y83530D01*
X277055Y83892D01*
X276787Y84150D01*
X276518Y84253D01*
X276173D01*
G01X276518D02*
X276748Y84408D01*
X276940Y84667D01*
X277017Y84977D01*
X276940Y85287D01*
X276748Y85545D01*
X276403Y85700D01*
X276058Y85648D01*
X275713Y85442D01*
G01X278200Y81567D02*
X280500D01*
G01X281683Y82600D02*
Y85700D01*
X282642D01*
X282948Y85545D01*
X283140Y85338D01*
X283217Y84925D01*
X283140Y84512D01*
X282910Y84253D01*
X282642Y84098D01*
X281683D01*
G01X282642D02*
X283217Y82600D01*
G01X285780Y84150D02*
X286547D01*
Y83220D01*
X286317Y82910D01*
X286048Y82703D01*
X285665Y82600D01*
X285282Y82703D01*
X285013Y82910D01*
X284783Y83220D01*
X284630Y83582D01*
X284553Y83995D01*
Y84357D01*
X284630Y84667D01*
X284783Y85028D01*
X285013Y85338D01*
X285243Y85545D01*
X285550Y85700D01*
X285818D01*
X286125Y85597D01*
X286355Y85390D01*
G01X287653Y82600D02*
Y85700D01*
X288650Y83117D01*
X289647Y85700D01*
Y82600D01*
G01X271400Y107000D02*
Y100800D01*
X268200D01*
Y107000D01*
X271400D01*
G01X270826Y122801D02*
X273428Y125403D01*
Y129625D01*
X261224D01*
Y115977D01*
X273428D01*
Y120199D01*
X270826Y122801D01*
G01X259939Y118758D02*
Y112558D01*
X258380D01*
G01X258100Y118758D02*
X259939D01*
G01X258300Y111900D02*
X263600D01*
Y108700D01*
X258800D01*
G01X264300Y108400D02*
Y114600D01*
X267500D01*
Y108400D01*
X264300D01*
G01X262650Y131057D02*
X264872D01*
X265337Y131210D01*
X265647Y131517D01*
X265750Y131900D01*
X265647Y132283D01*
X265337Y132590D01*
X264872Y132743D01*
X262650D01*
G01X265750Y135000D02*
X262650D01*
X263270Y134540D01*
G01X265750D02*
Y135460D01*
G01Y138560D02*
X262650D01*
X264872Y137142D01*
Y139058D01*
G01X271098Y135724D02*
Y141924D01*
X274298D01*
Y135724D01*
X271098D01*
G01X269468Y141029D02*
Y196550D01*
G01X259390Y141029D02*
X269468D01*
G01X273274Y149904D02*
Y143704D01*
X270074D01*
Y149904D01*
X273274D01*
G01X260107Y148550D02*
Y146328D01*
X260260Y145863D01*
X260567Y145553D01*
X260950Y145450D01*
X261333Y145553D01*
X261640Y145863D01*
X261793Y146328D01*
Y148550D01*
G01X263207Y145915D02*
X263437Y145657D01*
X263705Y145502D01*
X264050Y145450D01*
X264395Y145553D01*
X264663Y145760D01*
X264855Y146122D01*
X264893Y146535D01*
X264817Y146948D01*
X264625Y147207D01*
X264357Y147413D01*
X264088Y147465D01*
X263820Y147413D01*
X263475Y147207D01*
X263590Y148550D01*
X264625D01*
G01X257657Y181000D02*
Y152840D01*
G01X269468Y205130D02*
Y208800D01*
G01Y200800D02*
Y201740D01*
G01Y212820D02*
Y216630D01*
G01Y220830D02*
Y229510D01*
G01Y241560D02*
Y247721D01*
G01Y232320D02*
Y237230D01*
G01X267147Y255366D02*
X267400Y255616D01*
X267590Y256032D01*
X267717Y256616D01*
X267590Y257116D01*
X267337Y257449D01*
X266893Y257699D01*
X265183D01*
Y252699D01*
X267273D01*
X267717Y253032D01*
X267970Y253532D01*
X268097Y254116D01*
X267970Y254699D01*
X267590Y255199D01*
X267147Y255366D01*
X265183D01*
G01X270093Y252699D02*
Y257699D01*
X271740Y253532D01*
X273387Y257699D01*
Y252699D01*
G01X278233Y257282D02*
X277853Y257532D01*
X277410Y257699D01*
X276903D01*
X276333Y257449D01*
X275890Y257032D01*
X275573Y256532D01*
X275320Y255699D01*
X275257Y254949D01*
X275383Y254199D01*
X275573Y253699D01*
X275953Y253199D01*
X276397Y252866D01*
X276840Y252699D01*
X277283D01*
X277727Y252866D01*
X278107Y253116D01*
X278423Y253449D01*
G01X259700Y248700D02*
Y254900D01*
X262900D01*
Y248700D01*
X259700D01*
G01X273637Y250052D02*
Y243852D01*
X270437D01*
Y250052D01*
X273637D01*
G01X274850Y277100D02*
Y270900D01*
X271650D01*
Y277100D01*
X274850D01*
G01X256800Y261500D02*
X263000D01*
Y258300D01*
X256800D01*
Y261500D01*
G01X271000Y286100D02*
Y279900D01*
X267800D01*
Y286100D01*
X271000D01*
G01X260683Y356070D02*
X260875Y355760D01*
X261105Y355553D01*
X261373Y355450D01*
X261680Y355553D01*
X261910Y355760D01*
X262140Y356070D01*
X262217Y356483D01*
Y358550D01*
G01X263707Y355915D02*
X263937Y355657D01*
X264205Y355502D01*
X264550Y355450D01*
X264895Y355553D01*
X265163Y355760D01*
X265355Y356122D01*
X265393Y356535D01*
X265317Y356948D01*
X265125Y357207D01*
X264857Y357413D01*
X264588Y357465D01*
X264320Y357413D01*
X263975Y357207D01*
X264090Y358550D01*
X265125D01*
G01X265361Y366210D02*
X271561D01*
Y363010D01*
X265361D01*
Y366210D01*
G01X271561Y367010D02*
X265361D01*
Y370210D01*
X271561D01*
Y367010D01*
G01X261728Y384058D02*
X261460Y383697D01*
X261230Y383490D01*
X260923Y383387D01*
X260655Y383490D01*
X260463Y383697D01*
X260310Y384007D01*
X260272Y384368D01*
X260310Y384678D01*
X260463Y384988D01*
X260693Y385247D01*
X260962Y385350D01*
X261268Y385247D01*
X261537Y384937D01*
X261690Y384472D01*
X261728Y383955D01*
X261652Y383283D01*
X261537Y382922D01*
X261345Y382560D01*
X261077Y382302D01*
X260808Y382250D01*
X260540Y382353D01*
X260348Y382612D01*
G01X265361Y386943D02*
X271561D01*
Y383743D01*
X265361D01*
Y386943D01*
G01X271561Y379475D02*
X265361D01*
Y382675D01*
X271561D01*
Y379475D01*
G01X268400Y401100D02*
X274600D01*
Y397900D01*
X268400D01*
Y401100D01*
G01X268600Y421500D02*
Y415300D01*
X265400D01*
Y421500D01*
X268600D01*
G01X266400Y422200D02*
Y428400D01*
X269600D01*
Y422200D01*
X266400D01*
G01X273500Y428400D02*
Y422200D01*
X270300D01*
Y428400D01*
X273500D01*
G01X263500Y428300D02*
Y422100D01*
X260300D01*
Y428300D01*
X263500D01*
G01Y434645D02*
X273300D01*
G01X274339Y439548D02*
X274646Y439496D01*
X274914Y439290D01*
X275144Y438980D01*
X275297Y438618D01*
X275374Y438205D01*
Y437791D01*
X275297Y437378D01*
X275144Y437016D01*
X274914Y436706D01*
X274646Y436500D01*
X274339Y436448D01*
X274032Y436500D01*
X273764Y436706D01*
X273534Y437016D01*
X273381Y437378D01*
X273304Y437791D01*
Y438205D01*
X273381Y438618D01*
X273534Y438980D01*
X273764Y439290D01*
X274032Y439496D01*
X274339Y439548D01*
G01X270932Y437895D02*
X270779Y437740D01*
X270664Y437481D01*
X270587Y437120D01*
X270664Y436810D01*
X270817Y436603D01*
X271086Y436448D01*
X272121D01*
Y439548D01*
X270856D01*
X270587Y439341D01*
X270434Y439031D01*
X270357Y438670D01*
X270434Y438308D01*
X270664Y437998D01*
X270932Y437895D01*
X272121D01*
G01X268139Y439548D02*
Y436448D01*
X268599Y437068D01*
G01Y439548D02*
X267679D01*
G01X264579D02*
Y436448D01*
X265997Y438670D01*
X264081D01*
G01X279293Y-670269D02*
X279893Y-669469D01*
X280593Y-669069D01*
X281393Y-668936D01*
X282393Y-669203D01*
X283093Y-669869D01*
X283293Y-670669D01*
X283193Y-671470D01*
X282793Y-672136D01*
X280793Y-673469D01*
X279893Y-674403D01*
X279293Y-675736D01*
X279093Y-676936D01*
X283293D01*
G01X289193Y-668936D02*
X288393Y-669203D01*
X287793Y-669869D01*
X287393Y-670669D01*
X287093Y-671736D01*
X286993Y-672936D01*
X287093Y-674136D01*
X287393Y-675203D01*
X287793Y-676003D01*
X288393Y-676669D01*
X289193Y-676936D01*
X289993Y-676669D01*
X290593Y-676003D01*
X290993Y-675203D01*
X291293Y-674136D01*
X291393Y-672936D01*
X291293Y-671736D01*
X290993Y-670669D01*
X290593Y-669869D01*
X289993Y-669203D01*
X289193Y-668936D01*
G01X295293Y-670269D02*
X295893Y-669469D01*
X296593Y-669069D01*
X297393Y-668936D01*
X298393Y-669203D01*
X299093Y-669869D01*
X299293Y-670669D01*
X299193Y-671470D01*
X298793Y-672136D01*
X296793Y-673469D01*
X295893Y-674403D01*
X295293Y-675736D01*
X295093Y-676936D01*
X299293D01*
G01X303293Y-670269D02*
X303893Y-669469D01*
X304593Y-669069D01*
X305393Y-668936D01*
X306393Y-669203D01*
X307093Y-669869D01*
X307293Y-670669D01*
X307193Y-671470D01*
X306793Y-672136D01*
X304793Y-673469D01*
X303893Y-674403D01*
X303293Y-675736D01*
X303093Y-676936D01*
X307293D01*
G01X311393Y-677203D02*
X314993Y-668936D01*
G01X321193Y-676936D02*
Y-668936D01*
X319993Y-670536D01*
G01Y-676936D02*
X322393D01*
G01X327293Y-670269D02*
X327893Y-669469D01*
X328593Y-669069D01*
X329393Y-668936D01*
X330393Y-669203D01*
X331093Y-669869D01*
X331293Y-670669D01*
X331193Y-671470D01*
X330793Y-672136D01*
X328793Y-673469D01*
X327893Y-674403D01*
X327293Y-675736D01*
X327093Y-676936D01*
X331293D01*
G01X335393Y-677203D02*
X338993Y-668936D01*
G01X345193D02*
X344393Y-669203D01*
X343793Y-669869D01*
X343393Y-670669D01*
X343093Y-671736D01*
X342993Y-672936D01*
X343093Y-674136D01*
X343393Y-675203D01*
X343793Y-676003D01*
X344393Y-676669D01*
X345193Y-676936D01*
X345993Y-676669D01*
X346593Y-676003D01*
X346993Y-675203D01*
X347293Y-674136D01*
X347393Y-672936D01*
X347293Y-671736D01*
X346993Y-670669D01*
X346593Y-669869D01*
X345993Y-669203D01*
X345193Y-668936D01*
G01X351493Y-676003D02*
X352193Y-676669D01*
X352993Y-676936D01*
X353793Y-676669D01*
X354493Y-675870D01*
X354993Y-674669D01*
X355193Y-673469D01*
Y-672003D01*
X354993Y-670803D01*
X354493Y-669736D01*
X353893Y-669203D01*
X353193Y-668936D01*
X352393Y-669203D01*
X351793Y-669736D01*
X351393Y-670536D01*
X351193Y-671603D01*
X351393Y-672536D01*
X351893Y-673469D01*
X352493Y-674003D01*
X353193Y-674136D01*
X353993Y-673870D01*
X354593Y-673203D01*
X355193Y-672003D01*
G01X278993Y-651936D02*
Y-643936D01*
X280993D01*
X281793Y-644336D01*
X282393Y-644869D01*
X282893Y-645669D01*
X283293Y-646603D01*
X283393Y-647936D01*
X283293Y-649269D01*
X282893Y-650203D01*
X282393Y-651003D01*
X281793Y-651536D01*
X280993Y-651936D01*
X278993D01*
G01X286693D02*
X289193Y-643936D01*
X291693Y-651936D01*
G01X290793Y-649136D02*
X287593D01*
G01X297193Y-643936D02*
X296393Y-644203D01*
X295793Y-644869D01*
X295393Y-645669D01*
X295093Y-646736D01*
X294993Y-647936D01*
X295093Y-649136D01*
X295393Y-650203D01*
X295793Y-651003D01*
X296393Y-651669D01*
X297193Y-651936D01*
X297993Y-651669D01*
X298593Y-651003D01*
X298993Y-650203D01*
X299293Y-649136D01*
X299393Y-647936D01*
X299293Y-646736D01*
X298993Y-645669D01*
X298593Y-644869D01*
X297993Y-644203D01*
X297193Y-643936D01*
G01X303293Y-651936D02*
Y-643936D01*
X307093D01*
G01X305693Y-647803D02*
X303293D01*
G01X313193Y-643936D02*
X312393Y-644203D01*
X311793Y-644869D01*
X311393Y-645669D01*
X311093Y-646736D01*
X310993Y-647936D01*
X311093Y-649136D01*
X311393Y-650203D01*
X311793Y-651003D01*
X312393Y-651669D01*
X313193Y-651936D01*
X313993Y-651669D01*
X314593Y-651003D01*
X314993Y-650203D01*
X315293Y-649136D01*
X315393Y-647936D01*
X315293Y-646736D01*
X314993Y-645669D01*
X314593Y-644869D01*
X313993Y-644203D01*
X313193Y-643936D01*
G01X321193D02*
Y-651936D01*
G01X318893Y-643936D02*
X323493D01*
G01X326593Y-651936D02*
Y-643936D01*
X329193Y-650603D01*
X331793Y-643936D01*
Y-651936D01*
G01X334993D02*
Y-643936D01*
X336993D01*
X337793Y-644336D01*
X338393Y-644869D01*
X338893Y-645669D01*
X339293Y-646603D01*
X339393Y-647936D01*
X339293Y-649269D01*
X338893Y-650203D01*
X338393Y-651003D01*
X337793Y-651536D01*
X336993Y-651936D01*
X334993D01*
G01X347393Y-644603D02*
X346793Y-644203D01*
X346093Y-643936D01*
X345293D01*
X344393Y-644336D01*
X343693Y-645003D01*
X343193Y-645803D01*
X342793Y-647136D01*
X342693Y-648336D01*
X342893Y-649536D01*
X343193Y-650336D01*
X343793Y-651136D01*
X344493Y-651669D01*
X345193Y-651936D01*
X345893D01*
X346593Y-651669D01*
X347193Y-651269D01*
X347693Y-650736D01*
G01X350993Y-651936D02*
Y-643936D01*
X352993D01*
X353793Y-644336D01*
X354393Y-644869D01*
X354893Y-645669D01*
X355293Y-646603D01*
X355393Y-647936D01*
X355293Y-649269D01*
X354893Y-650203D01*
X354393Y-651003D01*
X353793Y-651536D01*
X352993Y-651936D01*
X350993D01*
G01X361193Y-643936D02*
X360393Y-644203D01*
X359793Y-644869D01*
X359393Y-645669D01*
X359093Y-646736D01*
X358993Y-647936D01*
X359093Y-649136D01*
X359393Y-650203D01*
X359793Y-651003D01*
X360393Y-651669D01*
X361193Y-651936D01*
X361993Y-651669D01*
X362593Y-651003D01*
X362993Y-650203D01*
X363293Y-649136D01*
X363393Y-647936D01*
X363293Y-646736D01*
X362993Y-645669D01*
X362593Y-644869D01*
X361993Y-644203D01*
X361193Y-643936D01*
G01X283353Y31063D02*
X272553D01*
G01X284400Y39900D02*
Y46100D01*
X287600D01*
Y39900D01*
X284400D01*
G01X279900D02*
Y46100D01*
X283100D01*
Y39900D01*
X279900D01*
G01X278600Y49100D02*
Y42900D01*
X275400D01*
Y49100D01*
X278600D01*
G01X284400Y60900D02*
Y67100D01*
X287600D01*
Y60900D01*
X284400D01*
G01X283600Y58831D02*
X295400D01*
Y50169D01*
X283600D01*
Y58831D01*
G01X275400Y74400D02*
Y80600D01*
X278600D01*
Y74400D01*
X275400D01*
G01X279400D02*
Y80600D01*
X282600D01*
Y74400D01*
X279400D01*
G01X283400D02*
Y80600D01*
X286600D01*
Y74400D01*
X283400D01*
G01X273100Y115100D02*
X275600D01*
X273100Y112600D01*
Y115100D01*
X275700Y112500D01*
X278300D01*
X279200Y111600D01*
Y92000D01*
X277500Y90300D01*
Y88200D01*
G01X285810Y91660D02*
X279610D01*
Y94860D01*
X285810D01*
Y91660D01*
G01X278320Y97750D02*
X272120D01*
Y100950D01*
X278320D01*
Y97750D01*
G01X282900Y113000D02*
Y106800D01*
X279700D01*
Y113000D01*
X282900D01*
G01X275700Y104300D02*
Y110500D01*
X278900D01*
Y104300D01*
X275700D01*
G01X286600Y104973D02*
Y107213D01*
G01X284975Y106000D02*
X288225D01*
G01X287755Y118292D02*
Y116052D01*
G01X289380Y117265D02*
X286130D01*
G01X286895Y124981D02*
Y118781D01*
X283695D01*
Y124981D01*
X286895D01*
G01X283695Y109286D02*
Y115486D01*
X286895D01*
Y109286D01*
X283695D01*
G01X282850Y120600D02*
Y114400D01*
X279650D01*
Y120600D01*
X282850D01*
G01X275650Y124850D02*
X281850D01*
Y121650D01*
X275650D01*
Y124850D01*
G01X278800Y120600D02*
Y114400D01*
X275600D01*
Y120600D01*
X278800D01*
G01X287900Y112087D02*
Y114513D01*
G01X291380Y131246D02*
Y133672D01*
G01X283695Y126867D02*
Y133067D01*
X286895D01*
Y126867D01*
X283695D01*
G01X276428Y135714D02*
Y141914D01*
X279628D01*
Y135714D01*
X276428D01*
G01X287658Y136803D02*
X281458D01*
Y140003D01*
X287658D01*
Y136803D01*
G01X275449Y126954D02*
Y133154D01*
X278649D01*
Y126954D01*
X275449D01*
G01X286109Y150031D02*
Y145431D01*
G01X296109Y145531D02*
Y145431D01*
X286109D01*
G01Y150031D02*
X296109D01*
G01X277284Y149904D02*
Y143704D01*
X274084D01*
Y149904D01*
X277284D01*
G01X299800Y150423D02*
X273434D01*
Y161500D01*
G01X282561Y165415D02*
Y162915D01*
G01X281948Y165415D02*
X283174D01*
G01X278835Y166106D02*
Y168606D01*
X279501D01*
X279715Y168481D01*
X279848Y168314D01*
X279901Y167981D01*
X279848Y167648D01*
X279688Y167439D01*
X279501Y167314D01*
X278835D01*
G01X279501D02*
X279901Y166106D01*
G01X315167Y214990D02*
Y162234D01*
X285245D01*
Y214990D01*
X315167D01*
G01X273434Y166100D02*
Y187300D01*
G01X282059Y169756D02*
Y172256D01*
X282699D01*
X282912Y172131D01*
X283072Y171839D01*
X283125Y171506D01*
X283072Y171173D01*
X282939Y170923D01*
X282699Y170798D01*
X282059D01*
G01X278755Y172405D02*
Y174905D01*
X279981Y172405D01*
Y174905D01*
G01X281899Y176055D02*
Y178555D01*
X282592Y176472D01*
X283285Y178555D01*
Y176055D01*
G01X278835Y181204D02*
Y178704D01*
X279901D01*
G01X282005Y182354D02*
Y184854D01*
G01X283019D02*
X282005Y183312D01*
G01X283179Y182354D02*
X282459Y184021D01*
G01X278835Y185504D02*
X278968Y185254D01*
X279128Y185087D01*
X279315Y185004D01*
X279528Y185087D01*
X279688Y185254D01*
X279848Y185504D01*
X279901Y185837D01*
Y187504D01*
G01X282032Y188653D02*
Y191153D01*
G01X283152D02*
Y188653D01*
G01Y189903D02*
X282032D01*
G01X279528Y192553D02*
X280061D01*
Y191803D01*
X279901Y191553D01*
X279715Y191386D01*
X279448Y191303D01*
X279181Y191386D01*
X278995Y191553D01*
X278835Y191803D01*
X278728Y192095D01*
X278675Y192428D01*
Y192720D01*
X278728Y192970D01*
X278835Y193261D01*
X278995Y193511D01*
X279155Y193678D01*
X279368Y193803D01*
X279555D01*
X279768Y193720D01*
X279928Y193553D01*
G01X282085Y194953D02*
Y197453D01*
X283099D01*
G01X282725Y196245D02*
X282085D01*
G01X279901Y197602D02*
X278835D01*
Y200102D01*
X279901D01*
G01X279475Y198894D02*
X278835D01*
G01X273434Y192300D02*
Y196000D01*
G01X282005Y201252D02*
Y203752D01*
X282539D01*
X282752Y203627D01*
X282912Y203460D01*
X283045Y203210D01*
X283152Y202919D01*
X283179Y202502D01*
X283152Y202085D01*
X283045Y201794D01*
X282912Y201544D01*
X282752Y201377D01*
X282539Y201252D01*
X282005D01*
G01X279955Y206193D02*
X279795Y206318D01*
X279608Y206401D01*
X279395D01*
X279155Y206276D01*
X278968Y206068D01*
X278835Y205818D01*
X278728Y205401D01*
X278701Y205026D01*
X278755Y204651D01*
X278835Y204401D01*
X278995Y204151D01*
X279181Y203984D01*
X279368Y203901D01*
X279555D01*
X279741Y203984D01*
X279901Y204109D01*
X280035Y204276D01*
G01X282805Y208884D02*
X282912Y209009D01*
X282992Y209218D01*
X283045Y209509D01*
X282992Y209759D01*
X282885Y209926D01*
X282699Y210051D01*
X281979D01*
Y207551D01*
X282859D01*
X283045Y207718D01*
X283152Y207968D01*
X283205Y208259D01*
X283152Y208551D01*
X282992Y208801D01*
X282805Y208884D01*
X281979D01*
G01X278701Y210201D02*
X279368Y212701D01*
X280035Y210201D01*
G01X279795Y211076D02*
X278941D01*
G01X273434Y205390D02*
Y208570D01*
G01Y200770D02*
Y201830D01*
G01Y220230D02*
Y226801D01*
X301855D01*
G01X273434Y212140D02*
Y216750D01*
G01X282149Y231253D02*
Y229031D01*
X282302Y228566D01*
X282609Y228256D01*
X282992Y228153D01*
X283375Y228256D01*
X283682Y228566D01*
X283835Y229031D01*
Y231253D01*
G01X286092Y228153D02*
Y231253D01*
X285632Y230633D01*
G01Y228153D02*
X286552D01*
G01X281182Y250252D02*
Y244052D01*
X277982D01*
Y250252D01*
X281182D01*
G01X286400Y289400D02*
Y295600D01*
X289600D01*
Y289400D01*
X286400D01*
G01X284633Y335507D02*
X284383Y335760D01*
X283967Y335950D01*
X283383Y336077D01*
X282883Y335950D01*
X282550Y335697D01*
X282300Y335253D01*
Y333543D01*
X287300D01*
Y335633D01*
X286967Y336077D01*
X286467Y336330D01*
X285883Y336457D01*
X285300Y336330D01*
X284800Y335950D01*
X284633Y335507D01*
Y333543D01*
G01X287300Y338453D02*
X282300D01*
X286467Y340100D01*
X282300Y341747D01*
X287300D01*
G01X282717Y346593D02*
X282467Y346213D01*
X282300Y345770D01*
Y345263D01*
X282550Y344693D01*
X282967Y344250D01*
X283467Y343933D01*
X284300Y343680D01*
X285050Y343617D01*
X285800Y343743D01*
X286300Y343933D01*
X286800Y344313D01*
X287133Y344757D01*
X287300Y345200D01*
Y345643D01*
X287133Y346087D01*
X286883Y346467D01*
X286550Y346783D01*
G01X282300Y355400D02*
X287300D01*
G01X282300Y353943D02*
Y356857D01*
G01X287300Y359233D02*
X282300D01*
Y360753D01*
X282550Y361260D01*
X283133Y361640D01*
X283800Y361767D01*
X284467Y361640D01*
X284967Y361323D01*
X285217Y360753D01*
Y359233D01*
G01X287300Y363953D02*
X282300D01*
X286467Y365600D01*
X282300Y367247D01*
X287300D01*
G01X286075Y376608D02*
Y370408D01*
X282875D01*
Y376608D01*
X286075D01*
G01X282500Y415200D02*
Y421400D01*
X285700D01*
Y415200D01*
X282500D01*
G01X285700Y434645D02*
X292000D01*
G01X276100D02*
X283000D01*
G01X298418Y-624819D02*
Y-618519D01*
X301394D01*
G01X300298Y-621564D02*
X298418D01*
G01X306206Y-618519D02*
X305579Y-618729D01*
X305109Y-619254D01*
X304796Y-619884D01*
X304561Y-620724D01*
X304483Y-621669D01*
X304561Y-622614D01*
X304796Y-623454D01*
X305109Y-624084D01*
X305579Y-624609D01*
X306206Y-624819D01*
X306833Y-624609D01*
X307303Y-624084D01*
X307616Y-623454D01*
X307851Y-622614D01*
X307929Y-621669D01*
X307851Y-620724D01*
X307616Y-619884D01*
X307303Y-619254D01*
X306833Y-618729D01*
X306206Y-618519D01*
G01X312506D02*
Y-624819D01*
G01X310704Y-618519D02*
X314308D01*
G01X316456Y-626919D02*
X321156D01*
G01X323069Y-624819D02*
Y-618519D01*
X325106Y-623769D01*
X327143Y-618519D01*
Y-624819D01*
G01X332816D02*
Y-620619D01*
G01Y-621354D02*
X332503Y-620934D01*
X332033Y-620724D01*
X331484Y-620619D01*
X330936Y-620829D01*
X330466Y-621249D01*
X330153Y-621879D01*
X329996Y-622719D01*
X330153Y-623559D01*
X330466Y-624189D01*
X330936Y-624609D01*
X331484Y-624819D01*
X332033Y-624714D01*
X332503Y-624399D01*
X332816Y-623979D01*
G01X336374Y-624819D02*
Y-620619D01*
G01Y-621669D02*
X336688Y-621144D01*
X337158Y-620724D01*
X337784Y-620619D01*
X338333Y-620724D01*
X338803Y-621144D01*
X339038Y-621879D01*
Y-624819D01*
G01X345416D02*
Y-620619D01*
G01Y-621354D02*
X345103Y-620934D01*
X344633Y-620724D01*
X344084Y-620619D01*
X343536Y-620829D01*
X343066Y-621249D01*
X342753Y-621879D01*
X342596Y-622719D01*
X342753Y-623559D01*
X343066Y-624189D01*
X343536Y-624609D01*
X344084Y-624819D01*
X344633Y-624714D01*
X345103Y-624399D01*
X345416Y-623979D01*
G01X349209Y-626394D02*
X349758Y-626814D01*
X350384Y-626919D01*
X350933Y-626814D01*
X351403Y-626289D01*
X351716Y-625554D01*
Y-620619D01*
G01Y-621459D02*
X351403Y-621039D01*
X350933Y-620724D01*
X350384Y-620619D01*
X349758Y-620829D01*
X349366Y-621249D01*
X349053Y-621984D01*
X348896Y-622719D01*
X348974Y-623349D01*
X349288Y-624084D01*
X349758Y-624609D01*
X350384Y-624819D01*
X350854Y-624714D01*
X351403Y-624294D01*
X351716Y-623874D01*
G01X355431Y-621984D02*
X357938D01*
X357703Y-621249D01*
X357311Y-620829D01*
X356763Y-620619D01*
X356214Y-620724D01*
X355744Y-621039D01*
X355431Y-621774D01*
X355274Y-622404D01*
Y-623034D01*
X355431Y-623664D01*
X355823Y-624294D01*
X356293Y-624714D01*
X356841Y-624819D01*
X357389Y-624609D01*
X357938Y-623979D01*
G01X360556Y-624819D02*
Y-620619D01*
G01Y-621774D02*
X360791Y-621249D01*
X361183Y-620829D01*
X361731Y-620619D01*
X362279Y-620829D01*
X362671Y-621249D01*
X362906Y-621774D01*
Y-624819D01*
G01Y-621774D02*
X363141Y-621249D01*
X363533Y-620829D01*
X364081Y-620619D01*
X364629Y-620829D01*
X365021Y-621249D01*
X365256Y-621879D01*
Y-624819D01*
G01X368031Y-621984D02*
X370538D01*
X370303Y-621249D01*
X369911Y-620829D01*
X369363Y-620619D01*
X368814Y-620724D01*
X368344Y-621039D01*
X368031Y-621774D01*
X367874Y-622404D01*
Y-623034D01*
X368031Y-623664D01*
X368423Y-624294D01*
X368893Y-624714D01*
X369441Y-624819D01*
X369989Y-624609D01*
X370538Y-623979D01*
G01X374174Y-624819D02*
Y-620619D01*
G01Y-621669D02*
X374488Y-621144D01*
X374958Y-620724D01*
X375584Y-620619D01*
X376133Y-620724D01*
X376603Y-621144D01*
X376838Y-621879D01*
Y-624819D01*
G01X381806Y-618519D02*
Y-624819D01*
G01X380709Y-620619D02*
X382903D01*
G01X385756Y-626919D02*
X390456D01*
G01X395033Y-621459D02*
X395346Y-621144D01*
X395581Y-620619D01*
X395738Y-619884D01*
X395581Y-619254D01*
X395268Y-618834D01*
X394719Y-618519D01*
X392604D01*
Y-624819D01*
X395189D01*
X395738Y-624399D01*
X396051Y-623769D01*
X396208Y-623034D01*
X396051Y-622299D01*
X395581Y-621669D01*
X395033Y-621459D01*
X392604D01*
G01X398983Y-624819D02*
Y-618519D01*
X400549D01*
X401176Y-618834D01*
X401646Y-619254D01*
X402038Y-619884D01*
X402351Y-620619D01*
X402429Y-621669D01*
X402351Y-622719D01*
X402038Y-623454D01*
X401646Y-624084D01*
X401176Y-624504D01*
X400549Y-624819D01*
X398983D01*
G01X292520Y16640D02*
Y17040D01*
G01Y23040D02*
Y31063D01*
X290353D01*
G01X288645Y39903D02*
Y46103D01*
X291845D01*
Y39903D01*
X288645D01*
G01X295468Y38596D02*
Y36356D01*
G01X297093Y37569D02*
X293843D01*
G01X296800Y50613D02*
Y48187D01*
G01X301473Y39804D02*
X298373D01*
Y40570D01*
X298528Y40877D01*
X298735Y41107D01*
X299045Y41299D01*
X299406Y41452D01*
X299923Y41490D01*
X300440Y41452D01*
X300801Y41299D01*
X301111Y41107D01*
X301318Y40877D01*
X301473Y40570D01*
Y39804D01*
G01Y43747D02*
X298373D01*
X298993Y43287D01*
G01X301473D02*
Y44207D01*
G01X298373Y46847D02*
X298476Y46540D01*
X298735Y46310D01*
X299045Y46157D01*
X299458Y46042D01*
X299923Y46004D01*
X300388Y46042D01*
X300801Y46157D01*
X301111Y46310D01*
X301370Y46540D01*
X301473Y46847D01*
X301370Y47154D01*
X301111Y47384D01*
X300801Y47537D01*
X300388Y47652D01*
X299923Y47690D01*
X299458Y47652D01*
X299045Y47537D01*
X298735Y47384D01*
X298476Y47154D01*
X298373Y46847D01*
G01X294302Y46978D02*
X297002Y46878D01*
X293902D01*
G01X297174Y47271D02*
X293630D01*
Y40185D01*
X297174D01*
Y47193D01*
G01X291600Y67100D02*
Y60900D01*
X288400D01*
Y67100D01*
X291600D01*
G01X298900Y58600D02*
X305100D01*
Y55400D01*
X298900D01*
Y58600D01*
G01X292907Y63300D02*
Y61078D01*
X293060Y60613D01*
X293367Y60303D01*
X293750Y60200D01*
X294133Y60303D01*
X294440Y60613D01*
X294593Y61078D01*
Y63300D01*
G01X296850Y60200D02*
Y63300D01*
X296390Y62680D01*
G01Y60200D02*
X297310D01*
G01X299222Y61492D02*
X299490Y61853D01*
X299720Y62060D01*
X300027Y62163D01*
X300295Y62060D01*
X300487Y61853D01*
X300640Y61543D01*
X300678Y61182D01*
X300640Y60872D01*
X300487Y60562D01*
X300257Y60303D01*
X299988Y60200D01*
X299682Y60303D01*
X299413Y60613D01*
X299260Y61078D01*
X299222Y61595D01*
X299298Y62267D01*
X299413Y62628D01*
X299605Y62990D01*
X299873Y63248D01*
X300142Y63300D01*
X300410Y63197D01*
X300602Y62938D01*
G01X299100Y77900D02*
X292900D01*
Y81100D01*
X299100D01*
Y77900D01*
G01X307600D02*
X301400D01*
Y81100D01*
X307600D01*
Y77900D01*
G01X291307Y87000D02*
Y90100D01*
X292073D01*
X292380Y89945D01*
X292610Y89738D01*
X292802Y89428D01*
X292955Y89067D01*
X292993Y88550D01*
X292955Y88033D01*
X292802Y87672D01*
X292610Y87362D01*
X292380Y87155D01*
X292073Y87000D01*
X291307D01*
G01X295250D02*
Y90100D01*
X294790Y89480D01*
G01Y87000D02*
X295710D01*
G01X298350D02*
X298618Y87052D01*
X298925Y87207D01*
X299117Y87465D01*
X299193Y87827D01*
X299117Y88188D01*
X298887Y88498D01*
X298542Y88653D01*
X298158D01*
X297928Y88757D01*
X297737Y89015D01*
X297660Y89377D01*
X297775Y89738D01*
X298043Y89997D01*
X298350Y90100D01*
X298657Y89997D01*
X298925Y89738D01*
X299040Y89377D01*
X298963Y89015D01*
X298772Y88757D01*
X298542Y88653D01*
X298158D01*
X297813Y88498D01*
X297583Y88188D01*
X297507Y87827D01*
X297583Y87465D01*
X297775Y87207D01*
X298082Y87052D01*
X298350Y87000D01*
G01X298020Y82100D02*
X290930D01*
Y85900D01*
X298020D01*
G01X298620Y82100D02*
X291430D01*
Y85900D01*
X298620D01*
G01X299020Y82100D02*
X291930D01*
Y85900D01*
X299070D01*
Y82150D01*
G01X300807Y87000D02*
Y90100D01*
X301573D01*
X301880Y89945D01*
X302110Y89738D01*
X302302Y89428D01*
X302455Y89067D01*
X302493Y88550D01*
X302455Y88033D01*
X302302Y87672D01*
X302110Y87362D01*
X301880Y87155D01*
X301573Y87000D01*
X300807D01*
G01X304750D02*
Y90100D01*
X304290Y89480D01*
G01Y87000D02*
X305210D01*
G01X307198Y87362D02*
X307467Y87103D01*
X307773Y87000D01*
X308080Y87103D01*
X308348Y87413D01*
X308540Y87878D01*
X308617Y88343D01*
Y88912D01*
X308540Y89377D01*
X308348Y89790D01*
X308118Y89997D01*
X307850Y90100D01*
X307543Y89997D01*
X307313Y89790D01*
X307160Y89480D01*
X307083Y89067D01*
X307160Y88705D01*
X307352Y88343D01*
X307582Y88137D01*
X307850Y88085D01*
X308157Y88188D01*
X308387Y88447D01*
X308617Y88912D01*
G01X307520Y82100D02*
X300430D01*
Y85900D01*
X307520D01*
G01X308120Y82100D02*
X300930D01*
Y85900D01*
X308120D01*
G01X308520Y82100D02*
X301430D01*
Y85900D01*
X308570D01*
Y82150D01*
G01X293600Y98800D02*
X287400D01*
Y102000D01*
X293600D01*
Y98800D01*
G01X304400Y100473D02*
Y102713D01*
G01X302775Y101500D02*
X306025D01*
G01X301100Y102813D02*
Y100387D01*
G01X300021Y104008D02*
Y105808D01*
G01X295621Y104008D02*
Y105808D01*
G01X300021Y104008D02*
X295621D01*
G01Y104608D02*
X300021D01*
G01Y105208D02*
X295621D01*
G01X300021Y116208D02*
Y105808D01*
X295621D01*
Y116208D01*
X300021D01*
G01X289180Y104008D02*
Y114408D01*
X293580D01*
Y104008D01*
X289180D01*
G01X301000Y121613D02*
Y119187D01*
G01X300021Y118059D02*
Y119859D01*
G01X295621Y118059D02*
Y119859D01*
G01X300021Y118059D02*
X295621D01*
G01Y118659D02*
X300021D01*
G01Y119259D02*
X295621D01*
G01X300021Y130259D02*
Y119859D01*
X295621D01*
Y130259D01*
X300021D01*
G01X289180Y118059D02*
Y128459D01*
X293580D01*
Y118059D01*
X289180D01*
G01X301000Y118127D02*
Y115887D01*
G01X302625Y117100D02*
X299375D01*
G01X294700Y116173D02*
Y118413D01*
G01X293075Y117200D02*
X296325D01*
G01X289180Y116208D02*
Y114408D01*
G01X293580Y116208D02*
Y114408D01*
G01X289180Y116208D02*
X293580D01*
G01Y115608D02*
X289180D01*
G01Y115008D02*
X293580D01*
G01X298427Y132700D02*
X296187D01*
G01X297400Y131075D02*
Y134325D01*
G01X289180Y130259D02*
Y128459D01*
G01X293580Y130259D02*
Y128459D01*
G01X289180Y130259D02*
X293580D01*
G01Y129659D02*
X289180D01*
G01Y129059D02*
X293580D01*
G01X301100Y131387D02*
Y133813D01*
G01X289180Y140597D02*
X299380D01*
Y135997D01*
X289180D01*
Y140597D01*
G01X294280D02*
Y135997D01*
G01X300336Y136672D02*
Y142872D01*
X303536D01*
Y136672D01*
X300336D01*
G01X291609Y150031D02*
Y145431D01*
G01X296109Y150031D02*
Y145431D01*
G01X290609Y150031D02*
Y145431D01*
G01X303536Y150972D02*
Y144772D01*
X300336D01*
Y150972D01*
X303536D01*
G01X299360Y141307D02*
X293160D01*
Y144507D01*
X299360D01*
Y141307D01*
G01X293757Y219078D02*
X293917Y218786D01*
X294131Y218620D01*
X294371Y218578D01*
X294584Y218620D01*
X294797Y218828D01*
X294931Y219078D01*
X294957Y219328D01*
X294904Y219620D01*
X294717Y219828D01*
X294531Y219911D01*
X294291D01*
G01X294531D02*
X294691Y220036D01*
X294824Y220245D01*
X294877Y220495D01*
X294824Y220745D01*
X294691Y220953D01*
X294451Y221078D01*
X294211Y221036D01*
X293971Y220870D01*
G01X290688Y220661D02*
X290848Y220911D01*
X291035Y221036D01*
X291248Y221078D01*
X291515Y220995D01*
X291702Y220786D01*
X291755Y220536D01*
X291728Y220286D01*
X291622Y220078D01*
X291088Y219661D01*
X290848Y219370D01*
X290688Y218953D01*
X290635Y218578D01*
X291755D01*
G01X288045D02*
Y221078D01*
X287725Y220578D01*
G01Y218578D02*
X288365D01*
G01X299139Y298994D02*
Y302094D01*
X300059D01*
X300366Y301939D01*
X300596Y301577D01*
X300673Y301164D01*
X300596Y300751D01*
X300404Y300441D01*
X300059Y300286D01*
X299139D01*
G01X302163Y302094D02*
Y299872D01*
X302316Y299407D01*
X302623Y299097D01*
X303006Y298994D01*
X303389Y299097D01*
X303696Y299407D01*
X303849Y299872D01*
Y302094D01*
G01X306566Y298994D02*
Y302094D01*
X305148Y299872D01*
X307064D01*
G01X309206Y298994D02*
Y302094D01*
X308746Y301474D01*
G01Y298994D02*
X309666D01*
G01X301477Y290114D02*
Y296314D01*
X304677D01*
Y290114D01*
X301477D01*
G01X293600Y295600D02*
Y289400D01*
X290400D01*
Y295600D01*
X293600D01*
G01X300600Y296100D02*
Y289900D01*
X297400D01*
Y296100D01*
X300600D01*
G01X302100Y309900D02*
X295900D01*
Y313100D01*
X302100D01*
Y309900D01*
G01X295900Y308600D02*
X302100D01*
Y305400D01*
X295900D01*
Y308600D01*
G01X291333Y319707D02*
X293555D01*
X294020Y319860D01*
X294330Y320167D01*
X294433Y320550D01*
X294330Y320933D01*
X294020Y321240D01*
X293555Y321393D01*
X291333D01*
G01X293968Y322807D02*
X294226Y323037D01*
X294381Y323305D01*
X294433Y323650D01*
X294330Y323995D01*
X294123Y324263D01*
X293761Y324455D01*
X293348Y324493D01*
X292935Y324417D01*
X292676Y324225D01*
X292470Y323957D01*
X292418Y323688D01*
X292470Y323420D01*
X292676Y323075D01*
X291333Y323190D01*
Y324225D01*
G01X293141Y326022D02*
X292780Y326290D01*
X292573Y326520D01*
X292470Y326827D01*
X292573Y327095D01*
X292780Y327287D01*
X293090Y327440D01*
X293451Y327478D01*
X293761Y327440D01*
X294071Y327287D01*
X294330Y327057D01*
X294433Y326788D01*
X294330Y326482D01*
X294020Y326213D01*
X293555Y326060D01*
X293038Y326022D01*
X292366Y326098D01*
X292005Y326213D01*
X291643Y326405D01*
X291385Y326673D01*
X291333Y326942D01*
X291436Y327210D01*
X291695Y327402D01*
G01X307602Y333118D02*
X295398D01*
Y317882D01*
X307602D01*
Y323627D01*
X304730Y325500D01*
X307602Y327373D01*
Y333118D01*
G01X294133Y350070D02*
X294325Y349760D01*
X294555Y349553D01*
X294823Y349450D01*
X295130Y349553D01*
X295360Y349760D01*
X295590Y350070D01*
X295667Y350483D01*
Y352550D01*
G01X298000Y349450D02*
Y352550D01*
X297540Y351930D01*
G01Y349450D02*
X298460D01*
G01X301100Y352550D02*
X300793Y352447D01*
X300563Y352188D01*
X300410Y351878D01*
X300295Y351465D01*
X300257Y351000D01*
X300295Y350535D01*
X300410Y350122D01*
X300563Y349812D01*
X300793Y349553D01*
X301100Y349450D01*
X301407Y349553D01*
X301637Y349812D01*
X301790Y350122D01*
X301905Y350535D01*
X301943Y351000D01*
X301905Y351465D01*
X301790Y351878D01*
X301637Y352188D01*
X301407Y352447D01*
X301100Y352550D01*
G01X297823Y361950D02*
X297900Y362622D01*
X298015Y363190D01*
X298168Y363707D01*
X298360Y364275D01*
X298667Y365050D01*
X297133D01*
G01X294825Y356908D02*
X288625D01*
Y360108D01*
X294825D01*
Y356908D01*
G01X286900Y374300D02*
X293100D01*
Y371100D01*
X286900D01*
Y374300D01*
G01X288625Y369108D02*
X294825D01*
Y365908D01*
X288625D01*
Y369108D01*
G01X294825Y361408D02*
X288625D01*
Y364608D01*
X294825D01*
Y361408D01*
G01X295250Y380950D02*
Y384050D01*
X294790Y383430D01*
G01Y380950D02*
X295710D01*
G01X298350D02*
Y384050D01*
X297890Y383430D01*
G01Y380950D02*
X298810D01*
G01X288161Y393200D02*
X294361D01*
Y390000D01*
X288161D01*
Y393200D01*
G01X294361Y385900D02*
X288161D01*
Y389100D01*
X294361D01*
Y385900D01*
G01X300889Y440408D02*
X301196Y440356D01*
X301464Y440150D01*
X301694Y439840D01*
X301847Y439478D01*
X301924Y439065D01*
Y438651D01*
X301847Y438238D01*
X301694Y437876D01*
X301464Y437566D01*
X301196Y437360D01*
X300889Y437308D01*
X300582Y437360D01*
X300314Y437566D01*
X300084Y437876D01*
X299931Y438238D01*
X299854Y438651D01*
Y439065D01*
X299931Y439478D01*
X300084Y439840D01*
X300314Y440150D01*
X300582Y440356D01*
X300889Y440408D01*
G01X297482Y438755D02*
X297329Y438600D01*
X297214Y438341D01*
X297137Y437980D01*
X297214Y437670D01*
X297367Y437463D01*
X297636Y437308D01*
X298671D01*
Y440408D01*
X297406D01*
X297137Y440201D01*
X296984Y439891D01*
X296907Y439530D01*
X296984Y439168D01*
X297214Y438858D01*
X297482Y438755D01*
X298671D01*
G01X294689Y440408D02*
Y437308D01*
X295149Y437928D01*
G01Y440408D02*
X294229D01*
G01X308268Y5473D02*
X315945D01*
Y-6338D01*
X329725D01*
Y5473D01*
X337402D01*
Y6065D01*
G01X308268D02*
Y5473D01*
G01Y15465D02*
Y15065D01*
G01X302430Y32044D02*
X302737Y31786D01*
X303082Y31631D01*
X303388D01*
X303695Y31786D01*
X303925Y32044D01*
X304040Y32406D01*
X303963Y32768D01*
X303772Y33078D01*
X303427Y33284D01*
X302967Y33388D01*
X302698Y33594D01*
X302583Y33956D01*
X302660Y34318D01*
X302852Y34576D01*
X303120Y34731D01*
X303388D01*
X303657Y34628D01*
X303887Y34369D01*
G01X305185Y34731D02*
X305722Y31631D01*
X306335Y34731D01*
X306948Y31631D01*
X307485Y34731D01*
G01X309358Y31631D02*
X309435Y32303D01*
X309550Y32871D01*
X309703Y33388D01*
X309895Y33956D01*
X310202Y34731D01*
X308668D01*
G01X310435Y29488D02*
X308268D01*
Y21465D01*
G01X314500Y64300D02*
X320700D01*
Y61100D01*
X314500D01*
Y64300D01*
G01X314745Y54000D02*
Y57100D01*
G01X316355D02*
Y54000D01*
G01Y55550D02*
X314745D01*
G01X318573Y54000D02*
X318650Y54672D01*
X318765Y55240D01*
X318918Y55757D01*
X319110Y56325D01*
X319417Y57100D01*
X317883D01*
G01X313335Y79348D02*
Y77126D01*
X313488Y76661D01*
X313795Y76351D01*
X314178Y76248D01*
X314561Y76351D01*
X314868Y76661D01*
X315021Y77126D01*
Y79348D01*
G01X316435Y76868D02*
X316665Y76506D01*
X316971Y76300D01*
X317316Y76248D01*
X317623Y76300D01*
X317930Y76558D01*
X318121Y76868D01*
X318160Y77178D01*
X318083Y77540D01*
X317815Y77798D01*
X317546Y77901D01*
X317201D01*
G01X317546D02*
X317776Y78056D01*
X317968Y78315D01*
X318045Y78625D01*
X317968Y78935D01*
X317776Y79193D01*
X317431Y79348D01*
X317086Y79296D01*
X316741Y79090D01*
G01X319650Y78831D02*
X319880Y79141D01*
X320148Y79296D01*
X320455Y79348D01*
X320838Y79245D01*
X321106Y78986D01*
X321183Y78676D01*
X321145Y78366D01*
X320991Y78108D01*
X320225Y77591D01*
X319880Y77230D01*
X319650Y76713D01*
X319573Y76248D01*
X321183D01*
G01X327977Y66071D02*
X314623D01*
Y74929D01*
X327977D01*
Y66071D01*
G01X317666Y107418D02*
Y101218D01*
X314466D01*
Y107418D01*
X317666D01*
G01X313200Y102908D02*
Y100482D01*
G01X312861Y104008D02*
Y105808D01*
G01X308461Y104008D02*
Y105808D01*
G01X312861Y104008D02*
X308461D01*
G01Y104608D02*
X312861D01*
G01Y105208D02*
X308461D01*
G01X312861Y116208D02*
Y105808D01*
X308461D01*
Y116208D01*
X312861D01*
G01X302059Y104008D02*
Y114408D01*
X306459D01*
Y104008D01*
X302059D01*
G01Y118059D02*
Y128459D01*
X306459D01*
Y118059D01*
X302059D01*
G01X314148Y120941D02*
Y118515D01*
G01X312861Y118059D02*
Y119859D01*
G01X308461Y118059D02*
Y119859D01*
G01X312861Y118059D02*
X308461D01*
G01Y118659D02*
X312861D01*
G01Y119259D02*
X308461D01*
G01X312861Y130259D02*
Y119859D01*
X308461D01*
Y130259D01*
X312861D01*
G01X318300Y124500D02*
Y118300D01*
X315100D01*
Y124500D01*
X318300D01*
G01X314466Y109285D02*
Y115485D01*
X317666D01*
Y109285D01*
X314466D01*
G01X315199Y115582D02*
Y117822D01*
G01X313574Y116609D02*
X316824D01*
G01X307467Y113454D02*
Y115880D01*
G01X302059Y116208D02*
Y114408D01*
G01X306459Y116208D02*
Y114408D01*
G01X302059Y116208D02*
X306459D01*
G01Y115608D02*
X302059D01*
G01Y115008D02*
X306459D01*
G01X302059Y130259D02*
Y128459D01*
G01X306459Y130259D02*
Y128459D01*
G01X302059Y130259D02*
X306459D01*
G01Y129659D02*
X302059D01*
G01Y129059D02*
X306459D01*
G01X315223Y129612D02*
Y127372D01*
G01X316848Y128585D02*
X313598D01*
G01X306700Y135900D02*
X312900D01*
Y132700D01*
X306700D01*
Y135900D01*
G01X312336Y136772D02*
Y142972D01*
X315536D01*
Y136772D01*
X312336D01*
G01X308336D02*
Y142972D01*
X311536D01*
Y136772D01*
X308336D01*
G01X304336D02*
Y142972D01*
X307536D01*
Y136772D01*
X304336D01*
G01X315580Y130901D02*
X317802D01*
X318267Y131054D01*
X318577Y131361D01*
X318680Y131744D01*
X318577Y132127D01*
X318267Y132434D01*
X317802Y132587D01*
X315580D01*
G01X318060Y134001D02*
X318422Y134231D01*
X318628Y134537D01*
X318680Y134882D01*
X318628Y135189D01*
X318370Y135496D01*
X318060Y135687D01*
X317750Y135726D01*
X317388Y135649D01*
X317130Y135381D01*
X317027Y135112D01*
Y134767D01*
G01Y135112D02*
X316872Y135342D01*
X316613Y135534D01*
X316303Y135611D01*
X315993Y135534D01*
X315735Y135342D01*
X315580Y134997D01*
X315632Y134652D01*
X315838Y134307D01*
G01X318318Y137292D02*
X318577Y137561D01*
X318680Y137867D01*
X318577Y138174D01*
X318267Y138442D01*
X317802Y138634D01*
X317337Y138711D01*
X316768D01*
X316303Y138634D01*
X315890Y138442D01*
X315683Y138212D01*
X315580Y137944D01*
X315683Y137637D01*
X315890Y137407D01*
X316200Y137254D01*
X316613Y137177D01*
X316975Y137254D01*
X317337Y137446D01*
X317543Y137676D01*
X317595Y137944D01*
X317492Y138251D01*
X317233Y138481D01*
X316768Y138711D01*
G01X311536Y150972D02*
Y144772D01*
X308336D01*
Y150972D01*
X311536D01*
G01X315536D02*
Y144772D01*
X312336D01*
Y150972D01*
X315536D01*
G01X307536D02*
Y144772D01*
X304336D01*
Y150972D01*
X307536D01*
G01X316336Y144772D02*
Y150972D01*
X319536D01*
Y144772D01*
X316336D01*
G01X308620Y226043D02*
X302020D01*
Y239043D01*
X308620D01*
Y226043D01*
G01X317021Y226019D02*
X310421D01*
Y239019D01*
X317021D01*
Y226019D01*
G01X312789Y218870D02*
X312975Y218661D01*
X313189Y218578D01*
X313402Y218661D01*
X313589Y218911D01*
X313722Y219286D01*
X313775Y219661D01*
Y220120D01*
X313722Y220495D01*
X313589Y220828D01*
X313429Y220995D01*
X313242Y221078D01*
X313029Y220995D01*
X312869Y220828D01*
X312762Y220578D01*
X312709Y220245D01*
X312762Y219953D01*
X312895Y219661D01*
X313055Y219495D01*
X313242Y219453D01*
X313455Y219536D01*
X313615Y219745D01*
X313775Y220120D01*
G01X310092Y218578D02*
X310279Y218620D01*
X310492Y218745D01*
X310625Y218953D01*
X310679Y219245D01*
X310625Y219536D01*
X310465Y219786D01*
X310225Y219911D01*
X309959D01*
X309799Y219995D01*
X309665Y220203D01*
X309612Y220495D01*
X309692Y220786D01*
X309879Y220995D01*
X310092Y221078D01*
X310305Y220995D01*
X310492Y220786D01*
X310572Y220495D01*
X310519Y220203D01*
X310385Y219995D01*
X310225Y219911D01*
X309959D01*
X309719Y219786D01*
X309559Y219536D01*
X309505Y219245D01*
X309559Y218953D01*
X309692Y218745D01*
X309905Y218620D01*
X310092Y218578D01*
G01X306890D02*
X306943Y219120D01*
X307023Y219578D01*
X307130Y219995D01*
X307263Y220453D01*
X307476Y221078D01*
X306410D01*
G01X308925Y226801D02*
X310310D01*
G01X302020Y232543D02*
X308620D01*
G01X310421Y232519D02*
X317021D01*
G01X317505Y242355D02*
X311416D01*
Y271095D01*
X317405D01*
G01X309981Y271656D02*
X303781D01*
Y274856D01*
X309981D01*
Y271656D01*
G01X315725Y282144D02*
Y282010D01*
X318827D01*
G01X303781Y286692D02*
X309981D01*
Y283492D01*
X303781D01*
Y286692D01*
G01Y282688D02*
X309981D01*
Y279488D01*
X303781D01*
Y282688D01*
G01Y278700D02*
X309981D01*
Y275500D01*
X303781D01*
Y278700D01*
G01X315374Y296932D02*
Y303532D01*
X328374D01*
Y296932D01*
X315374D01*
G01X318827Y290278D02*
X315725D01*
G01D02*
Y290144D01*
G01X305487Y290114D02*
Y296314D01*
X308687D01*
Y290114D01*
X305487D01*
G01X315374Y304382D02*
Y310982D01*
X328374D01*
Y304382D01*
X315374D01*
G01X303400Y313100D02*
X309600D01*
Y309900D01*
X303400D01*
Y313100D01*
G01X312600Y328100D02*
Y321900D01*
X309400D01*
Y328100D01*
X312600D01*
G01X301976Y360149D02*
Y363849D01*
G01X321662Y353173D02*
X301976D01*
Y353449D01*
G01Y383049D02*
Y386749D01*
G01X319197Y398065D02*
X316097D01*
Y398985D01*
X316252Y399292D01*
X316614Y399522D01*
X317027Y399599D01*
X317440Y399522D01*
X317750Y399330D01*
X317905Y398985D01*
Y398065D01*
G01X319300Y401242D02*
X316097Y402622D01*
G01X319197Y404150D02*
X316097D01*
X319197Y405914D01*
X316097D01*
G01X319300Y408132D02*
X319249Y408055D01*
X319145D01*
X319094Y408132D01*
X319145Y408209D01*
X319249D01*
X319300Y408132D01*
G01X317905D02*
X317854Y408055D01*
X317750D01*
X317699Y408132D01*
X317750Y408209D01*
X317854D01*
X317905Y408132D01*
G01X319197Y410389D02*
X316097D01*
Y411155D01*
X316252Y411462D01*
X316459Y411692D01*
X316769Y411884D01*
X317130Y412037D01*
X317647Y412075D01*
X318164Y412037D01*
X318525Y411884D01*
X318835Y411692D01*
X319042Y411462D01*
X319197Y411155D01*
Y410389D01*
G01Y413374D02*
X316097Y414332D01*
X319197Y415290D01*
G01X318112Y414945D02*
Y413719D01*
G01X316097Y417432D02*
X316200Y417125D01*
X316459Y416895D01*
X316769Y416742D01*
X317182Y416627D01*
X317647Y416589D01*
X318112Y416627D01*
X318525Y416742D01*
X318835Y416895D01*
X319094Y417125D01*
X319197Y417432D01*
X319094Y417739D01*
X318835Y417969D01*
X318525Y418122D01*
X318112Y418237D01*
X317647Y418275D01*
X317182Y418237D01*
X316769Y418122D01*
X316459Y417969D01*
X316200Y417739D01*
X316097Y417432D01*
G01X319197Y419804D02*
X316097D01*
Y421260D01*
G01X317595Y420724D02*
Y419804D01*
G01X316097Y423632D02*
X316200Y423325D01*
X316459Y423095D01*
X316769Y422942D01*
X317182Y422827D01*
X317647Y422789D01*
X318112Y422827D01*
X318525Y422942D01*
X318835Y423095D01*
X319094Y423325D01*
X319197Y423632D01*
X319094Y423939D01*
X318835Y424169D01*
X318525Y424322D01*
X318112Y424437D01*
X317647Y424475D01*
X317182Y424437D01*
X316769Y424322D01*
X316459Y424169D01*
X316200Y423939D01*
X316097Y423632D01*
G01Y426732D02*
X319197D01*
G01X316097Y425850D02*
Y427614D01*
G01X319197Y428835D02*
X316097D01*
X318680Y429832D01*
X316097Y430829D01*
X319197D01*
G01Y432089D02*
X316097D01*
Y432855D01*
X316252Y433162D01*
X316459Y433392D01*
X316769Y433584D01*
X317130Y433737D01*
X317647Y433775D01*
X318164Y433737D01*
X318525Y433584D01*
X318835Y433392D01*
X319042Y433162D01*
X319197Y432855D01*
Y432089D01*
G01X316355Y436875D02*
X316200Y436645D01*
X316097Y436377D01*
Y436070D01*
X316252Y435725D01*
X316510Y435457D01*
X316820Y435265D01*
X317337Y435112D01*
X317802Y435074D01*
X318267Y435150D01*
X318577Y435265D01*
X318887Y435495D01*
X319094Y435764D01*
X319197Y436032D01*
Y436300D01*
X319094Y436569D01*
X318939Y436799D01*
X318732Y436990D01*
G01X319197Y438289D02*
X316097D01*
Y439055D01*
X316252Y439362D01*
X316459Y439592D01*
X316769Y439784D01*
X317130Y439937D01*
X317647Y439975D01*
X318164Y439937D01*
X318525Y439784D01*
X318835Y439592D01*
X319042Y439362D01*
X319197Y439055D01*
Y438289D01*
G01X316097Y442232D02*
X316200Y441925D01*
X316459Y441695D01*
X316769Y441542D01*
X317182Y441427D01*
X317647Y441389D01*
X318112Y441427D01*
X318525Y441542D01*
X318835Y441695D01*
X319094Y441925D01*
X319197Y442232D01*
X319094Y442539D01*
X318835Y442769D01*
X318525Y442922D01*
X318112Y443037D01*
X317647Y443075D01*
X317182Y443037D01*
X316769Y442922D01*
X316459Y442769D01*
X316200Y442539D01*
X316097Y442232D01*
G01X301976Y393449D02*
Y393725D01*
X321662D01*
Y393449D01*
G01X306564Y436338D02*
Y439438D01*
G01X308174D02*
Y436338D01*
G01Y437888D02*
X306564D01*
G01X309626Y436958D02*
X309856Y436596D01*
X310162Y436390D01*
X310507Y436338D01*
X310814Y436390D01*
X311121Y436648D01*
X311312Y436958D01*
X311351Y437268D01*
X311274Y437630D01*
X311006Y437888D01*
X310737Y437991D01*
X310392D01*
G01X310737D02*
X310967Y438146D01*
X311159Y438405D01*
X311236Y438715D01*
X311159Y439025D01*
X310967Y439283D01*
X310622Y439438D01*
X310277Y439386D01*
X309932Y439180D01*
G01X328235Y29488D02*
X317435D01*
G01X332361Y102327D02*
X329261D01*
Y103093D01*
X329416Y103400D01*
X329623Y103630D01*
X329933Y103822D01*
X330294Y103975D01*
X330811Y104013D01*
X331328Y103975D01*
X331689Y103822D01*
X331999Y103630D01*
X332206Y103400D01*
X332361Y103093D01*
Y102327D01*
G01X329778Y105542D02*
X329468Y105772D01*
X329313Y106040D01*
X329261Y106347D01*
X329364Y106730D01*
X329623Y106998D01*
X329933Y107075D01*
X330243Y107037D01*
X330501Y106883D01*
X331018Y106117D01*
X331379Y105772D01*
X331896Y105542D01*
X332361Y105465D01*
Y107075D01*
G01X328000Y102307D02*
X324900D01*
Y103073D01*
X325055Y103380D01*
X325262Y103610D01*
X325572Y103802D01*
X325933Y103955D01*
X326450Y103993D01*
X326967Y103955D01*
X327328Y103802D01*
X327638Y103610D01*
X327845Y103380D01*
X328000Y103073D01*
Y102307D01*
G01X327380Y105407D02*
X327742Y105637D01*
X327948Y105943D01*
X328000Y106288D01*
X327948Y106595D01*
X327690Y106902D01*
X327380Y107093D01*
X327070Y107132D01*
X326708Y107055D01*
X326450Y106787D01*
X326347Y106518D01*
Y106173D01*
G01Y106518D02*
X326192Y106748D01*
X325933Y106940D01*
X325623Y107017D01*
X325313Y106940D01*
X325055Y106748D01*
X324900Y106403D01*
X324952Y106058D01*
X325158Y105713D01*
G01X331200Y109107D02*
X328100D01*
Y109873D01*
X328255Y110180D01*
X328462Y110410D01*
X328772Y110602D01*
X329133Y110755D01*
X329650Y110793D01*
X330167Y110755D01*
X330528Y110602D01*
X330838Y110410D01*
X331045Y110180D01*
X331200Y109873D01*
Y109107D01*
G01X329908Y112322D02*
X329547Y112590D01*
X329340Y112820D01*
X329237Y113127D01*
X329340Y113395D01*
X329547Y113587D01*
X329857Y113740D01*
X330218Y113778D01*
X330528Y113740D01*
X330838Y113587D01*
X331097Y113357D01*
X331200Y113088D01*
X331097Y112782D01*
X330787Y112513D01*
X330322Y112360D01*
X329805Y112322D01*
X329133Y112398D01*
X328772Y112513D01*
X328410Y112705D01*
X328152Y112973D01*
X328100Y113242D01*
X328203Y113510D01*
X328462Y113702D01*
G01X326800Y109107D02*
X323700D01*
Y109873D01*
X323855Y110180D01*
X324062Y110410D01*
X324372Y110602D01*
X324733Y110755D01*
X325250Y110793D01*
X325767Y110755D01*
X326128Y110602D01*
X326438Y110410D01*
X326645Y110180D01*
X326800Y109873D01*
Y109107D01*
G01Y112973D02*
X326128Y113050D01*
X325560Y113165D01*
X325043Y113318D01*
X324475Y113510D01*
X323700Y113817D01*
Y112283D01*
G01X338000Y121800D02*
Y115200D01*
X325000D01*
Y121800D01*
X338000D01*
G01X319272Y115602D02*
Y121802D01*
X322472D01*
Y115602D01*
X319272D01*
G01X319349Y126202D02*
Y138210D01*
G01Y128306D02*
Y126202D01*
X320153D01*
G01Y138210D02*
X319349D01*
Y135706D01*
G01X330553Y126202D02*
X331357D01*
Y128506D01*
G01X330727Y142823D02*
X324527D01*
Y146023D01*
X330727D01*
Y142823D01*
G01X324527Y150039D02*
X330727D01*
Y146839D01*
X324527D01*
Y150039D01*
G01X320400Y143400D02*
Y149600D01*
X323600D01*
Y143400D01*
X320400D01*
G01X331357Y138210D02*
X330553D01*
G01X326978Y160900D02*
Y150423D01*
X320900D01*
G01X326978Y172100D02*
Y167100D01*
G01Y184200D02*
Y176700D01*
G01Y226801D02*
Y189100D01*
G01X330897Y205507D02*
X330742Y205660D01*
X330483Y205775D01*
X330122Y205852D01*
X329812Y205775D01*
X329605Y205622D01*
X329450Y205353D01*
Y204318D01*
X332550D01*
Y205583D01*
X332343Y205852D01*
X332033Y206005D01*
X331672Y206082D01*
X331310Y206005D01*
X331000Y205775D01*
X330897Y205507D01*
Y204318D01*
G01X332550Y207303D02*
X329450D01*
X332033Y208300D01*
X329450Y209297D01*
X332550D01*
G01X329708Y212243D02*
X329553Y212013D01*
X329450Y211745D01*
Y211438D01*
X329605Y211093D01*
X329863Y210825D01*
X330173Y210633D01*
X330690Y210480D01*
X331155Y210442D01*
X331620Y210518D01*
X331930Y210633D01*
X332240Y210863D01*
X332447Y211132D01*
X332550Y211400D01*
Y211668D01*
X332447Y211937D01*
X332292Y212167D01*
X332085Y212358D01*
G01X332550Y216833D02*
X329450D01*
Y217792D01*
X329605Y218098D01*
X329812Y218290D01*
X330225Y218367D01*
X330638Y218290D01*
X330897Y218060D01*
X331052Y217792D01*
Y216833D01*
G01Y217792D02*
X332550Y218367D01*
G01Y219742D02*
X329450Y220700D01*
X332550Y221658D01*
G01X331465Y221313D02*
Y220087D01*
G01X332550Y222803D02*
X329450D01*
X332033Y223800D01*
X329450Y224797D01*
X332550D01*
G01X325422Y225995D02*
X318822D01*
Y238995D01*
X325422D01*
Y225995D01*
G01X333823Y225971D02*
X327223D01*
Y238971D01*
X333823D01*
Y225971D01*
G01X317189Y226801D02*
X318766D01*
G01X325740D02*
X326978D01*
G01X318822Y232495D02*
X325422D01*
G01X327223Y232471D02*
X333823D01*
G01X324827Y282010D02*
X327929D01*
Y282144D01*
G01X331425Y280497D02*
Y274297D01*
X328225D01*
Y280497D01*
X331425D01*
G01X325980Y274340D02*
X319780D01*
Y277540D01*
X325980D01*
Y274340D01*
G01X321874Y303532D02*
Y296932D01*
G01X322727Y290278D02*
X320927D01*
G01X327929Y290144D02*
Y290278D01*
X324827D01*
G01X330900Y298700D02*
Y304900D01*
X334100D01*
Y298700D01*
X330900D01*
G01X324759Y293216D02*
X318559D01*
Y296416D01*
X324759D01*
Y293216D01*
G01X321874Y310982D02*
Y304382D01*
G01X323700Y312000D02*
X328300D01*
G01X328200Y322000D02*
X328300D01*
Y312000D01*
G01X323700D02*
Y322000D01*
G01X332500D02*
Y315800D01*
X329300D01*
Y322000D01*
X332500D01*
G01X323700Y317500D02*
X328300D01*
G01X323700Y322000D02*
X328300D01*
G01X323700Y316500D02*
X328300D01*
G01X321662Y361849D02*
Y360149D01*
G01Y353449D02*
Y353173D01*
G01X328400Y360100D02*
X334600D01*
Y356900D01*
X328400D01*
Y360100D01*
G01Y378100D02*
X334600D01*
Y374900D01*
X328400D01*
Y378100D01*
G01Y369100D02*
X334600D01*
Y365900D01*
X328400D01*
Y369100D01*
G01Y373600D02*
X334600D01*
Y370400D01*
X328400D01*
Y373600D01*
G01Y364600D02*
X334600D01*
Y361400D01*
X328400D01*
Y364600D01*
G01X327428Y386708D02*
X327160Y386347D01*
X326930Y386140D01*
X326623Y386037D01*
X326355Y386140D01*
X326163Y386347D01*
X326010Y386657D01*
X325972Y387018D01*
X326010Y387328D01*
X326163Y387638D01*
X326393Y387897D01*
X326662Y388000D01*
X326968Y387897D01*
X327237Y387587D01*
X327390Y387122D01*
X327428Y386605D01*
X327352Y385933D01*
X327237Y385572D01*
X327045Y385210D01*
X326777Y384952D01*
X326508Y384900D01*
X326240Y385003D01*
X326048Y385262D01*
G01X321662Y386749D02*
Y385049D01*
G01X328400Y382600D02*
X334600D01*
Y379400D01*
X328400D01*
Y382600D01*
G01Y387100D02*
X334600D01*
Y383900D01*
X328400D01*
Y387100D01*
G01X323801Y398058D02*
X320701D01*
Y399017D01*
X320856Y399323D01*
X321063Y399515D01*
X321476Y399592D01*
X321889Y399515D01*
X322148Y399285D01*
X322303Y399017D01*
Y398058D01*
G01Y399017D02*
X323801Y399592D01*
G01X322406Y401350D02*
Y402577D01*
X322044Y402462D01*
X321838Y402270D01*
X321734Y402002D01*
X321786Y401733D01*
X321941Y401503D01*
X322303Y401350D01*
X322613Y401273D01*
X322923D01*
X323233Y401350D01*
X323543Y401542D01*
X323749Y401772D01*
X323801Y402040D01*
X323698Y402308D01*
X323388Y402577D01*
G01X321734Y404335D02*
X323801Y405025D01*
X321734Y405715D01*
G01X323904Y408125D02*
X323853Y408048D01*
X323749D01*
X323698Y408125D01*
X323749Y408202D01*
X323853D01*
X323904Y408125D01*
G01X322509D02*
X322458Y408048D01*
X322354D01*
X322303Y408125D01*
X322354Y408202D01*
X322458D01*
X322509Y408125D01*
G01X323801Y410382D02*
X320701D01*
Y411148D01*
X320856Y411455D01*
X321063Y411685D01*
X321373Y411877D01*
X321734Y412030D01*
X322251Y412068D01*
X322768Y412030D01*
X323129Y411877D01*
X323439Y411685D01*
X323646Y411455D01*
X323801Y411148D01*
Y410382D01*
G01X326145Y419200D02*
Y422300D01*
G01X327755D02*
Y419200D01*
G01Y420750D02*
X326145D01*
G01X329322Y421783D02*
X329552Y422093D01*
X329820Y422248D01*
X330127Y422300D01*
X330510Y422197D01*
X330778Y421938D01*
X330855Y421628D01*
X330817Y421318D01*
X330663Y421060D01*
X329897Y420543D01*
X329552Y420182D01*
X329322Y419665D01*
X329245Y419200D01*
X330855D01*
G01X333457Y420853D02*
X333610Y421008D01*
X333725Y421267D01*
X333802Y421628D01*
X333725Y421938D01*
X333572Y422145D01*
X333303Y422300D01*
X332268D01*
Y419200D01*
X333533D01*
X333802Y419407D01*
X333955Y419717D01*
X334032Y420078D01*
X333955Y420440D01*
X333725Y420750D01*
X333457Y420853D01*
X332268D01*
G01X336250Y419200D02*
Y422300D01*
X335790Y421680D01*
G01Y419200D02*
X336710D01*
G01X350089Y432809D02*
G03I-9450J0D01*
G01X349034Y6433D02*
X345934D01*
Y7392D01*
X346089Y7698D01*
X346296Y7890D01*
X346709Y7967D01*
X347122Y7890D01*
X347381Y7660D01*
X347536Y7392D01*
Y6433D01*
G01Y7392D02*
X349034Y7967D01*
G01X348621Y9495D02*
X348879Y9802D01*
X349034Y10147D01*
Y10453D01*
X348879Y10760D01*
X348621Y10990D01*
X348259Y11105D01*
X347897Y11028D01*
X347587Y10837D01*
X347381Y10492D01*
X347277Y10032D01*
X347071Y9763D01*
X346709Y9648D01*
X346347Y9725D01*
X346089Y9917D01*
X345934Y10185D01*
Y10453D01*
X346037Y10722D01*
X346296Y10952D01*
G01X345934Y13400D02*
X349034D01*
G01X345934Y12518D02*
Y14282D01*
G01X350067Y15350D02*
Y17650D01*
G01X347381Y19907D02*
X347226Y20060D01*
X346967Y20175D01*
X346606Y20252D01*
X346296Y20175D01*
X346089Y20022D01*
X345934Y19753D01*
Y18718D01*
X349034D01*
Y19983D01*
X348827Y20252D01*
X348517Y20405D01*
X348156Y20482D01*
X347794Y20405D01*
X347484Y20175D01*
X347381Y19907D01*
Y18718D01*
G01X345934Y22700D02*
X349034D01*
G01X345934Y21818D02*
Y23582D01*
G01X349034Y24918D02*
X345934D01*
X349034Y26682D01*
X345934D01*
G01X337402Y15065D02*
Y15465D01*
G01Y21465D02*
Y29488D01*
X335235D01*
G01X332700Y67600D02*
X338900D01*
Y64400D01*
X332700D01*
Y67600D01*
G01X338900Y68400D02*
X332700D01*
Y71600D01*
X338900D01*
Y68400D01*
G01X332700Y75600D02*
X338900D01*
Y72400D01*
X332700D01*
Y75600D01*
G01X344338Y86662D02*
Y89762D01*
G01X345948D02*
Y86662D01*
G01Y88212D02*
X344338D01*
G01X347591Y87024D02*
X347860Y86765D01*
X348166Y86662D01*
X348473Y86765D01*
X348741Y87075D01*
X348933Y87540D01*
X349010Y88005D01*
Y88574D01*
X348933Y89039D01*
X348741Y89452D01*
X348511Y89659D01*
X348243Y89762D01*
X347936Y89659D01*
X347706Y89452D01*
X347553Y89142D01*
X347476Y88729D01*
X347553Y88367D01*
X347745Y88005D01*
X347975Y87799D01*
X348243Y87747D01*
X348550Y87850D01*
X348780Y88109D01*
X349010Y88574D01*
G01X341300Y102507D02*
X338200D01*
Y103273D01*
X338355Y103580D01*
X338562Y103810D01*
X338872Y104002D01*
X339233Y104155D01*
X339750Y104193D01*
X340267Y104155D01*
X340628Y104002D01*
X340938Y103810D01*
X341145Y103580D01*
X341300Y103273D01*
Y102507D01*
G01X338200Y106450D02*
X338303Y106143D01*
X338562Y105913D01*
X338872Y105760D01*
X339285Y105645D01*
X339750Y105607D01*
X340215Y105645D01*
X340628Y105760D01*
X340938Y105913D01*
X341197Y106143D01*
X341300Y106450D01*
X341197Y106757D01*
X340938Y106987D01*
X340628Y107140D01*
X340215Y107255D01*
X339750Y107293D01*
X339285Y107255D01*
X338872Y107140D01*
X338562Y106987D01*
X338303Y106757D01*
X338200Y106450D01*
G01X336800Y102507D02*
X333700D01*
Y103273D01*
X333855Y103580D01*
X334062Y103810D01*
X334372Y104002D01*
X334733Y104155D01*
X335250Y104193D01*
X335767Y104155D01*
X336128Y104002D01*
X336438Y103810D01*
X336645Y103580D01*
X336800Y103273D01*
Y102507D01*
G01Y106450D02*
X333700D01*
X334320Y105990D01*
G01X336800D02*
Y106910D01*
G01X335500Y109307D02*
X332400D01*
Y110073D01*
X332555Y110380D01*
X332762Y110610D01*
X333072Y110802D01*
X333433Y110955D01*
X333950Y110993D01*
X334467Y110955D01*
X334828Y110802D01*
X335138Y110610D01*
X335345Y110380D01*
X335500Y110073D01*
Y109307D01*
G01X335035Y112407D02*
X335293Y112637D01*
X335448Y112905D01*
X335500Y113250D01*
X335397Y113595D01*
X335190Y113863D01*
X334828Y114055D01*
X334415Y114093D01*
X334002Y114017D01*
X333743Y113825D01*
X333537Y113557D01*
X333485Y113288D01*
X333537Y113020D01*
X333743Y112675D01*
X332400Y112790D01*
Y113825D01*
G01X339979Y109304D02*
X336879D01*
Y110070D01*
X337034Y110377D01*
X337241Y110607D01*
X337551Y110799D01*
X337912Y110952D01*
X338429Y110990D01*
X338946Y110952D01*
X339307Y110799D01*
X339617Y110607D01*
X339824Y110377D01*
X339979Y110070D01*
Y109304D01*
G01Y113707D02*
X336879D01*
X339101Y112289D01*
Y114205D01*
G01X331500Y115200D02*
Y121800D01*
G01X344862Y124131D02*
X341762D01*
Y125051D01*
X341917Y125358D01*
X342279Y125588D01*
X342692Y125665D01*
X343105Y125588D01*
X343415Y125396D01*
X343570Y125051D01*
Y124131D01*
G01X342279Y127270D02*
X341969Y127500D01*
X341814Y127768D01*
X341762Y128075D01*
X341865Y128458D01*
X342124Y128726D01*
X342434Y128803D01*
X342744Y128765D01*
X343002Y128611D01*
X343519Y127845D01*
X343880Y127500D01*
X344397Y127270D01*
X344862Y127193D01*
Y128803D01*
G01X341762Y130140D02*
X344862Y131098D01*
X341762Y132056D01*
G01X344397Y133355D02*
X344655Y133585D01*
X344810Y133853D01*
X344862Y134198D01*
X344759Y134543D01*
X344552Y134811D01*
X344190Y135003D01*
X343777Y135041D01*
X343364Y134965D01*
X343105Y134773D01*
X342899Y134505D01*
X342847Y134236D01*
X342899Y133968D01*
X343105Y133623D01*
X341762Y133738D01*
Y134773D01*
G01X345895Y136148D02*
Y138448D01*
G01X344862Y139440D02*
X341762Y140398D01*
X344862Y141356D01*
G01X343777Y141011D02*
Y139785D01*
G01X341762Y142655D02*
X343984D01*
X344449Y142808D01*
X344759Y143115D01*
X344862Y143498D01*
X344759Y143881D01*
X344449Y144188D01*
X343984Y144341D01*
X341762D01*
G01X344862Y145793D02*
X341762Y147403D01*
G01Y145793D02*
X344862Y147403D01*
G01X333200Y136000D02*
X339800D01*
G01Y129500D02*
X333200D01*
Y142500D01*
X339800D01*
Y129500D01*
G01X332960Y127100D02*
X339160D01*
Y123900D01*
X332960D01*
Y127100D01*
G01X331357Y126202D02*
Y138210D01*
G01Y135606D02*
Y138210D01*
G01X331678Y143764D02*
Y149964D01*
X334878D01*
Y143764D01*
X331678D01*
G01X338925Y153311D02*
X332725D01*
Y156511D01*
X338925D01*
Y153311D01*
G01Y163311D02*
X332725D01*
Y166511D01*
X338925D01*
Y163311D01*
G01Y158311D02*
X332725D01*
Y161511D01*
X338925D01*
Y158311D01*
G01Y168311D02*
X332725D01*
Y171511D01*
X338925D01*
Y168311D01*
G01Y178311D02*
X332725D01*
Y181511D01*
X338925D01*
Y178311D01*
G01Y173311D02*
X332725D01*
Y176511D01*
X338925D01*
Y173311D01*
G01Y182326D02*
X332725D01*
Y185526D01*
X338925D01*
Y182326D01*
G01Y188311D02*
X332725D01*
Y191511D01*
X338925D01*
Y188311D01*
G01X338823Y235157D02*
Y228957D01*
X335623D01*
Y235157D01*
X338823D01*
G01X337794Y271125D02*
Y242355D01*
X331705D01*
G01Y271095D02*
X337794D01*
G01X345053Y275107D02*
X341953D01*
Y276027D01*
X342108Y276334D01*
X342470Y276564D01*
X342883Y276641D01*
X343296Y276564D01*
X343606Y276372D01*
X343761Y276027D01*
Y275107D01*
G01X345053Y278974D02*
X341953D01*
X342573Y278514D01*
G01X345053D02*
Y279434D01*
G01X341953Y281116D02*
X345053Y282074D01*
X341953Y283032D01*
G01X342470Y284446D02*
X342160Y284676D01*
X342005Y284944D01*
X341953Y285251D01*
X342056Y285634D01*
X342315Y285902D01*
X342625Y285979D01*
X342935Y285941D01*
X343193Y285787D01*
X343710Y285021D01*
X344071Y284676D01*
X344588Y284446D01*
X345053Y284369D01*
Y285979D01*
G01X346086Y287124D02*
Y289424D01*
G01X345053Y290416D02*
X341953Y291374D01*
X345053Y292332D01*
G01X343968Y291987D02*
Y290761D01*
G01X341953Y293631D02*
X344175D01*
X344640Y293784D01*
X344950Y294091D01*
X345053Y294474D01*
X344950Y294857D01*
X344640Y295164D01*
X344175Y295317D01*
X341953D01*
G01X345053Y296769D02*
X341953Y298379D01*
G01Y296769D02*
X345053Y298379D01*
G01X332239Y274297D02*
Y280497D01*
X335439D01*
Y274297D01*
X332239D01*
G01X339200Y280500D02*
Y274300D01*
X336000D01*
Y280500D01*
X339200D01*
G01X332228Y281677D02*
Y287877D01*
X335428D01*
Y281677D01*
X332228D01*
G01X338424Y290485D02*
X332224D01*
Y293685D01*
X338424D01*
Y290485D01*
G01X334900Y298700D02*
Y304900D01*
X338100D01*
Y298700D01*
X334900D01*
G01X332200Y297500D02*
X338400D01*
Y294300D01*
X332200D01*
Y297500D01*
G01X367693Y-679936D02*
Y-671936D01*
X366493Y-673536D01*
G01Y-679936D02*
X368893D01*
G01X373793Y-676603D02*
X374493Y-675669D01*
X375093Y-675136D01*
X375893Y-674869D01*
X376593Y-675136D01*
X377093Y-675669D01*
X377493Y-676469D01*
X377593Y-677403D01*
X377493Y-678203D01*
X377093Y-679003D01*
X376493Y-679669D01*
X375793Y-679936D01*
X374993Y-679669D01*
X374293Y-678870D01*
X373893Y-677669D01*
X373793Y-676336D01*
X373993Y-674603D01*
X374293Y-673669D01*
X374793Y-672736D01*
X375493Y-672069D01*
X376193Y-671936D01*
X376893Y-672203D01*
X377393Y-672869D01*
G01X383693Y-680203D02*
X383493Y-680069D01*
Y-679803D01*
X383693Y-679669D01*
X383893Y-679803D01*
Y-680069D01*
X383693Y-680203D01*
G01X389793Y-676603D02*
X390493Y-675669D01*
X391093Y-675136D01*
X391893Y-674869D01*
X392593Y-675136D01*
X393093Y-675669D01*
X393493Y-676469D01*
X393593Y-677403D01*
X393493Y-678203D01*
X393093Y-679003D01*
X392493Y-679669D01*
X391793Y-679936D01*
X390993Y-679669D01*
X390293Y-678870D01*
X389893Y-677669D01*
X389793Y-676336D01*
X389993Y-674603D01*
X390293Y-673669D01*
X390793Y-672736D01*
X391493Y-672069D01*
X392193Y-671936D01*
X392893Y-672203D01*
X393393Y-672869D01*
G01X369276Y-160891D02*
X374419D01*
G01X380768D02*
X385876D01*
Y-170491D01*
X369276D01*
Y-160891D01*
G01X374473Y13331D02*
X369364D01*
Y22931D01*
X385964D01*
Y13331D01*
G01X380840Y67381D02*
X385904D01*
Y57781D01*
X369304D01*
Y67381D01*
G01D02*
X374436D01*
G01X374509Y382603D02*
X369364D01*
Y392203D01*
X385964D01*
Y382603D01*
G01X389380Y-169617D02*
X389690Y-169425D01*
X389897Y-169195D01*
X390000Y-168927D01*
X389897Y-168620D01*
X389690Y-168390D01*
X389380Y-168160D01*
X388967Y-168083D01*
X386900D01*
G01X390000Y-165750D02*
X386900D01*
X387520Y-166210D01*
G01X390000D02*
Y-165290D01*
G01X388708Y-163378D02*
X388347Y-163110D01*
X388140Y-162880D01*
X388037Y-162573D01*
X388140Y-162305D01*
X388347Y-162113D01*
X388657Y-161960D01*
X389018Y-161922D01*
X389328Y-161960D01*
X389638Y-162113D01*
X389897Y-162343D01*
X390000Y-162612D01*
X389897Y-162918D01*
X389587Y-163187D01*
X389122Y-163340D01*
X388605Y-163378D01*
X387933Y-163302D01*
X387572Y-163187D01*
X387210Y-162995D01*
X386952Y-162727D01*
X386900Y-162458D01*
X387003Y-162190D01*
X387262Y-161998D01*
G01X389380Y14383D02*
X389690Y14575D01*
X389897Y14805D01*
X390000Y15073D01*
X389897Y15380D01*
X389690Y15610D01*
X389380Y15840D01*
X388967Y15917D01*
X386900D01*
G01X390000Y18250D02*
X386900D01*
X387520Y17790D01*
G01X390000D02*
Y18710D01*
G01X389638Y20698D02*
X389897Y20967D01*
X390000Y21273D01*
X389897Y21580D01*
X389587Y21848D01*
X389122Y22040D01*
X388657Y22117D01*
X388088D01*
X387623Y22040D01*
X387210Y21848D01*
X387003Y21618D01*
X386900Y21350D01*
X387003Y21043D01*
X387210Y20813D01*
X387520Y20660D01*
X387933Y20583D01*
X388295Y20660D01*
X388657Y20852D01*
X388863Y21082D01*
X388915Y21350D01*
X388812Y21657D01*
X388553Y21887D01*
X388088Y22117D01*
G01X385964Y13331D02*
X380913D01*
G01X389380Y58383D02*
X389690Y58575D01*
X389897Y58805D01*
X390000Y59073D01*
X389897Y59380D01*
X389690Y59610D01*
X389380Y59840D01*
X388967Y59917D01*
X386900D01*
G01X387417Y61522D02*
X387107Y61752D01*
X386952Y62020D01*
X386900Y62327D01*
X387003Y62710D01*
X387262Y62978D01*
X387572Y63055D01*
X387882Y63017D01*
X388140Y62863D01*
X388657Y62097D01*
X389018Y61752D01*
X389535Y61522D01*
X390000Y61445D01*
Y63055D01*
G01X389380Y64507D02*
X389742Y64737D01*
X389948Y65043D01*
X390000Y65388D01*
X389948Y65695D01*
X389690Y66002D01*
X389380Y66193D01*
X389070Y66232D01*
X388708Y66155D01*
X388450Y65887D01*
X388347Y65618D01*
Y65273D01*
G01Y65618D02*
X388192Y65848D01*
X387933Y66040D01*
X387623Y66117D01*
X387313Y66040D01*
X387055Y65848D01*
X386900Y65503D01*
X386952Y65158D01*
X387158Y64813D01*
G01X400539Y263200D02*
X407050D01*
Y253600D01*
X390450D01*
Y263200D01*
G01D02*
X396931D01*
G01X385964Y382603D02*
X380877D01*
G01X384380Y403383D02*
X384690Y403575D01*
X384897Y403805D01*
X385000Y404073D01*
X384897Y404380D01*
X384690Y404610D01*
X384380Y404840D01*
X383967Y404917D01*
X381900D01*
G01X382417Y406522D02*
X382107Y406752D01*
X381952Y407020D01*
X381900Y407327D01*
X382003Y407710D01*
X382262Y407978D01*
X382572Y408055D01*
X382882Y408017D01*
X383140Y407863D01*
X383657Y407097D01*
X384018Y406752D01*
X384535Y406522D01*
X385000Y406445D01*
Y408055D01*
G01X383708Y409622D02*
X383347Y409890D01*
X383140Y410120D01*
X383037Y410427D01*
X383140Y410695D01*
X383347Y410887D01*
X383657Y411040D01*
X384018Y411078D01*
X384328Y411040D01*
X384638Y410887D01*
X384897Y410657D01*
X385000Y410388D01*
X384897Y410082D01*
X384587Y409813D01*
X384122Y409660D01*
X383605Y409622D01*
X382933Y409698D01*
X382572Y409813D01*
X382210Y410005D01*
X381952Y410273D01*
X381900Y410542D01*
X382003Y410810D01*
X382262Y411002D01*
G01X396913Y407660D02*
X390450D01*
Y417260D01*
X407050D01*
Y407660D01*
G01X410533Y-66072D02*
X417050D01*
Y-75672D01*
X400450D01*
Y-66072D01*
G01D02*
X406943D01*
G01X406952Y209388D02*
X400450D01*
Y218988D01*
X417050D01*
Y209388D01*
G01X393380Y238383D02*
X393690Y238575D01*
X393897Y238805D01*
X394000Y239073D01*
X393897Y239380D01*
X393690Y239610D01*
X393380Y239840D01*
X392967Y239917D01*
X390900D01*
G01X393638Y241598D02*
X393897Y241867D01*
X394000Y242173D01*
X393897Y242480D01*
X393587Y242748D01*
X393122Y242940D01*
X392657Y243017D01*
X392088D01*
X391623Y242940D01*
X391210Y242748D01*
X391003Y242518D01*
X390900Y242250D01*
X391003Y241943D01*
X391210Y241713D01*
X391520Y241560D01*
X391933Y241483D01*
X392295Y241560D01*
X392657Y241752D01*
X392863Y241982D01*
X392915Y242250D01*
X392812Y242557D01*
X392553Y242787D01*
X392088Y243017D01*
G01X407050Y407660D02*
X400539D01*
G01X405380Y428383D02*
X405690Y428575D01*
X405897Y428805D01*
X406000Y429073D01*
X405897Y429380D01*
X405690Y429610D01*
X405380Y429840D01*
X404967Y429917D01*
X402900D01*
G01X406000Y432250D02*
X402900D01*
X403520Y431790D01*
G01X406000D02*
Y432710D01*
G01X403417Y434622D02*
X403107Y434852D01*
X402952Y435120D01*
X402900Y435427D01*
X403003Y435810D01*
X403262Y436078D01*
X403572Y436155D01*
X403882Y436117D01*
X404140Y435963D01*
X404657Y435197D01*
X405018Y434852D01*
X405535Y434622D01*
X406000Y434545D01*
Y436155D01*
G01X412693Y-679936D02*
Y-671936D01*
X411493Y-673536D01*
G01Y-679936D02*
X413893D01*
G01X420493D02*
X420693Y-678203D01*
X420993Y-676736D01*
X421393Y-675403D01*
X421893Y-673936D01*
X422693Y-671936D01*
X418693D01*
G01X428693Y-680203D02*
X428493Y-680069D01*
Y-679803D01*
X428693Y-679669D01*
X428893Y-679803D01*
Y-680069D01*
X428693Y-680203D01*
G01X434793Y-673269D02*
X435393Y-672469D01*
X436093Y-672069D01*
X436893Y-671936D01*
X437893Y-672203D01*
X438593Y-672869D01*
X438793Y-673669D01*
X438693Y-674470D01*
X438293Y-675136D01*
X436293Y-676469D01*
X435393Y-677403D01*
X434793Y-678736D01*
X434593Y-679936D01*
X438793D01*
G01X415380Y-94617D02*
X415690Y-94425D01*
X415897Y-94195D01*
X416000Y-93927D01*
X415897Y-93620D01*
X415690Y-93390D01*
X415380Y-93160D01*
X414967Y-93083D01*
X412900D01*
G01X413417Y-91478D02*
X413107Y-91248D01*
X412952Y-90980D01*
X412900Y-90673D01*
X413003Y-90290D01*
X413262Y-90022D01*
X413572Y-89945D01*
X413882Y-89983D01*
X414140Y-90137D01*
X414657Y-90903D01*
X415018Y-91248D01*
X415535Y-91478D01*
X416000Y-91555D01*
Y-89945D01*
G01X415535Y-88493D02*
X415793Y-88263D01*
X415948Y-87995D01*
X416000Y-87650D01*
X415897Y-87305D01*
X415690Y-87037D01*
X415328Y-86845D01*
X414915Y-86807D01*
X414502Y-86883D01*
X414243Y-87075D01*
X414037Y-87343D01*
X413985Y-87612D01*
X414037Y-87880D01*
X414243Y-88225D01*
X412900Y-88110D01*
Y-87075D01*
G01X417050Y209388D02*
X410524D01*
G01X415380Y230383D02*
X415690Y230575D01*
X415897Y230805D01*
X416000Y231073D01*
X415897Y231380D01*
X415690Y231610D01*
X415380Y231840D01*
X414967Y231917D01*
X412900D01*
G01X413417Y233522D02*
X413107Y233752D01*
X412952Y234020D01*
X412900Y234327D01*
X413003Y234710D01*
X413262Y234978D01*
X413572Y235055D01*
X413882Y235017D01*
X414140Y234863D01*
X414657Y234097D01*
X415018Y233752D01*
X415535Y233522D01*
X416000Y233445D01*
Y235055D01*
G01X413417Y236622D02*
X413107Y236852D01*
X412952Y237120D01*
X412900Y237427D01*
X413003Y237810D01*
X413262Y238078D01*
X413572Y238155D01*
X413882Y238117D01*
X414140Y237963D01*
X414657Y237197D01*
X415018Y236852D01*
X415535Y236622D01*
X416000Y236545D01*
Y238155D01*
G01X432493Y-654936D02*
Y-646936D01*
X434493D01*
X435293Y-647336D01*
X435893Y-647869D01*
X436393Y-648669D01*
X436793Y-649603D01*
X436893Y-650936D01*
X436793Y-652269D01*
X436393Y-653203D01*
X435893Y-654003D01*
X435293Y-654536D01*
X434493Y-654936D01*
X432493D01*
G01X448500Y-444000D02*
X443500D01*
G01X445450Y-454000D02*
X446550D01*
G01X438500Y-444000D02*
X436000D01*
Y-454000D01*
X436550D01*
G01X439395Y-438250D02*
X441005Y-435150D01*
G01X439395D02*
X441005Y-438250D01*
G01X442572Y-435667D02*
X442802Y-435357D01*
X443070Y-435202D01*
X443377Y-435150D01*
X443760Y-435253D01*
X444028Y-435512D01*
X444105Y-435822D01*
X444067Y-436132D01*
X443913Y-436390D01*
X443147Y-436907D01*
X442802Y-437268D01*
X442572Y-437785D01*
X442495Y-438250D01*
X444105D01*
G01X446860D02*
Y-435150D01*
X445442Y-437372D01*
X447358D01*
G01X445595Y-364550D02*
X447205Y-361450D01*
G01X445595D02*
X447205Y-364550D01*
G01X449500D02*
Y-361450D01*
X449040Y-362070D01*
G01Y-364550D02*
X449960D01*
G01X452600D02*
X452868Y-364498D01*
X453175Y-364343D01*
X453367Y-364085D01*
X453443Y-363723D01*
X453367Y-363362D01*
X453137Y-363052D01*
X452792Y-362897D01*
X452408D01*
X452178Y-362793D01*
X451987Y-362535D01*
X451910Y-362173D01*
X452025Y-361812D01*
X452293Y-361553D01*
X452600Y-361450D01*
X452907Y-361553D01*
X453175Y-361812D01*
X453290Y-362173D01*
X453213Y-362535D01*
X453022Y-362793D01*
X452792Y-362897D01*
X452408D01*
X452063Y-363052D01*
X451833Y-363362D01*
X451757Y-363723D01*
X451833Y-364085D01*
X452025Y-364343D01*
X452332Y-364498D01*
X452600Y-364550D01*
G01X436000Y-355000D02*
X438500D01*
G01X443500D02*
X448500D01*
G01X436550Y-345000D02*
X436000D01*
Y-355000D01*
G01X446550Y-345000D02*
X445450D01*
G01Y-333400D02*
X446550D01*
G01X438500Y-323400D02*
X436000D01*
Y-333400D01*
X436550D01*
G01X439095Y-317050D02*
X440705Y-313950D01*
G01X439095D02*
X440705Y-317050D01*
G01X442272Y-314467D02*
X442502Y-314157D01*
X442770Y-314002D01*
X443077Y-313950D01*
X443460Y-314053D01*
X443728Y-314312D01*
X443805Y-314622D01*
X443767Y-314932D01*
X443613Y-315190D01*
X442847Y-315707D01*
X442502Y-316068D01*
X442272Y-316585D01*
X442195Y-317050D01*
X443805D01*
G01X445257Y-316430D02*
X445487Y-316792D01*
X445793Y-316998D01*
X446138Y-317050D01*
X446445Y-316998D01*
X446752Y-316740D01*
X446943Y-316430D01*
X446982Y-316120D01*
X446905Y-315758D01*
X446637Y-315500D01*
X446368Y-315397D01*
X446023D01*
G01X446368D02*
X446598Y-315242D01*
X446790Y-314983D01*
X446867Y-314673D01*
X446790Y-314363D01*
X446598Y-314105D01*
X446253Y-313950D01*
X445908Y-314002D01*
X445563Y-314208D01*
G01X448500Y-323400D02*
X443500D01*
G01X445595Y-254550D02*
X447205Y-251450D01*
G01X445595D02*
X447205Y-254550D01*
G01X449500D02*
Y-251450D01*
X449040Y-252070D01*
G01Y-254550D02*
X449960D01*
G01X452523D02*
X452600Y-253878D01*
X452715Y-253310D01*
X452868Y-252793D01*
X453060Y-252225D01*
X453367Y-251450D01*
X451833D01*
G01X436000Y-245000D02*
X438500D01*
G01X443500D02*
X448500D01*
G01X436550Y-235000D02*
X436000D01*
Y-245000D01*
G01X446550Y-235000D02*
X445450D01*
G01Y2000D02*
X446550D01*
G01X438500Y12000D02*
X436000D01*
Y2000D01*
X436550D01*
G01X448500Y12000D02*
X443500D01*
G01X436000Y96000D02*
X438500D01*
G01X443500D02*
X448500D01*
G01X436550Y106000D02*
X436000D01*
Y96000D01*
G01X446550Y106000D02*
X445450D01*
G01Y116000D02*
X446550D01*
G01X438500Y126000D02*
X436000D01*
Y116000D01*
X436550D01*
G01X448500Y126000D02*
X443500D01*
G01X436000Y200000D02*
X438500D01*
G01X443500D02*
X448500D01*
G01X436550Y210000D02*
X436000D01*
Y200000D01*
G01X446550Y210000D02*
X445450D01*
G01X456000Y-444000D02*
X453500D01*
G01X455450Y-454000D02*
X456000D01*
Y-444000D01*
G01X453500Y-355000D02*
X456000D01*
Y-345000D01*
X455450D01*
G01Y-333400D02*
X456000D01*
Y-323400D01*
G01D02*
X453500D01*
G01Y-245000D02*
X456000D01*
Y-235000D01*
X455450D01*
G01Y2000D02*
X456000D01*
Y12000D01*
G01X454645Y17450D02*
X456255Y20550D01*
G01X454645D02*
X456255Y17450D01*
G01X457822Y18742D02*
X458090Y19103D01*
X458320Y19310D01*
X458627Y19413D01*
X458895Y19310D01*
X459087Y19103D01*
X459240Y18793D01*
X459278Y18432D01*
X459240Y18122D01*
X459087Y17812D01*
X458857Y17553D01*
X458588Y17450D01*
X458282Y17553D01*
X458013Y17863D01*
X457860Y18328D01*
X457822Y18845D01*
X457898Y19517D01*
X458013Y19878D01*
X458205Y20240D01*
X458473Y20498D01*
X458742Y20550D01*
X459010Y20447D01*
X459202Y20188D01*
G01X456000Y12000D02*
X453500D01*
G01X463550Y97595D02*
X460450Y99205D01*
G01Y97595D02*
X463550Y99205D01*
G01Y101500D02*
X460450D01*
X461070Y101040D01*
G01X463550D02*
Y101960D01*
G01X460967Y103872D02*
X460657Y104102D01*
X460502Y104370D01*
X460450Y104677D01*
X460553Y105060D01*
X460812Y105328D01*
X461122Y105405D01*
X461432Y105367D01*
X461690Y105213D01*
X462207Y104447D01*
X462568Y104102D01*
X463085Y103872D01*
X463550Y103795D01*
Y105405D01*
G01X453500Y96000D02*
X456000D01*
Y106000D01*
X455450D01*
G01X463550Y118095D02*
X460450Y119705D01*
G01Y118095D02*
X463550Y119705D01*
G01Y122000D02*
X460450D01*
X461070Y121540D01*
G01X463550D02*
Y122460D01*
G01Y125100D02*
X460450D01*
X461070Y124640D01*
G01X463550D02*
Y125560D01*
G01X455450Y116000D02*
X456000D01*
Y126000D01*
G01D02*
X453500D01*
G01X464050Y200145D02*
X460950Y201755D01*
G01Y200145D02*
X464050Y201755D01*
G01X463585Y203207D02*
X463843Y203437D01*
X463998Y203705D01*
X464050Y204050D01*
X463947Y204395D01*
X463740Y204663D01*
X463378Y204855D01*
X462965Y204893D01*
X462552Y204817D01*
X462293Y204625D01*
X462087Y204357D01*
X462035Y204088D01*
X462087Y203820D01*
X462293Y203475D01*
X460950Y203590D01*
Y204625D01*
G01X453500Y200000D02*
X456000D01*
Y210000D01*
X455450D01*
G01X480500Y417683D02*
X477400D01*
Y418603D01*
X477555Y418910D01*
X477917Y419140D01*
X478330Y419217D01*
X478743Y419140D01*
X479053Y418948D01*
X479208Y418603D01*
Y417683D01*
G01X480603Y420860D02*
X477400Y422240D01*
G01X480500Y423768D02*
X477400D01*
X480500Y425532D01*
X477400D01*
G01X480603Y427750D02*
X480552Y427673D01*
X480448D01*
X480397Y427750D01*
X480448Y427827D01*
X480552D01*
X480603Y427750D01*
G01X479208D02*
X479157Y427673D01*
X479053D01*
X479002Y427750D01*
X479053Y427827D01*
X479157D01*
X479208Y427750D01*
G01X480500Y430007D02*
X477400D01*
Y430773D01*
X477555Y431080D01*
X477762Y431310D01*
X478072Y431502D01*
X478433Y431655D01*
X478950Y431693D01*
X479467Y431655D01*
X479828Y431502D01*
X480138Y431310D01*
X480345Y431080D01*
X480500Y430773D01*
Y430007D01*
G01Y432992D02*
X477400Y433950D01*
X480500Y434908D01*
G01X479415Y434563D02*
Y433337D01*
G01X477400Y437050D02*
X477503Y436743D01*
X477762Y436513D01*
X478072Y436360D01*
X478485Y436245D01*
X478950Y436207D01*
X479415Y436245D01*
X479828Y436360D01*
X480138Y436513D01*
X480397Y436743D01*
X480500Y437050D01*
X480397Y437357D01*
X480138Y437587D01*
X479828Y437740D01*
X479415Y437855D01*
X478950Y437893D01*
X478485Y437855D01*
X478072Y437740D01*
X477762Y437587D01*
X477503Y437357D01*
X477400Y437050D01*
G01X480500Y439422D02*
X477400D01*
Y440878D01*
G01X478898Y440342D02*
Y439422D01*
G01X477400Y443250D02*
X477503Y442943D01*
X477762Y442713D01*
X478072Y442560D01*
X478485Y442445D01*
X478950Y442407D01*
X479415Y442445D01*
X479828Y442560D01*
X480138Y442713D01*
X480397Y442943D01*
X480500Y443250D01*
X480397Y443557D01*
X480138Y443787D01*
X479828Y443940D01*
X479415Y444055D01*
X478950Y444093D01*
X478485Y444055D01*
X478072Y443940D01*
X477762Y443787D01*
X477503Y443557D01*
X477400Y443250D01*
G01Y446350D02*
X480500D01*
G01X477400Y445468D02*
Y447232D01*
G01X480500Y448453D02*
X477400D01*
X479983Y449450D01*
X477400Y450447D01*
X480500D01*
G01Y451707D02*
X477400D01*
Y452473D01*
X477555Y452780D01*
X477762Y453010D01*
X478072Y453202D01*
X478433Y453355D01*
X478950Y453393D01*
X479467Y453355D01*
X479828Y453202D01*
X480138Y453010D01*
X480345Y452780D01*
X480500Y452473D01*
Y451707D01*
G01X477658Y456493D02*
X477503Y456263D01*
X477400Y455995D01*
Y455688D01*
X477555Y455343D01*
X477813Y455075D01*
X478123Y454883D01*
X478640Y454730D01*
X479105Y454692D01*
X479570Y454768D01*
X479880Y454883D01*
X480190Y455113D01*
X480397Y455382D01*
X480500Y455650D01*
Y455918D01*
X480397Y456187D01*
X480242Y456417D01*
X480035Y456608D01*
G01X480500Y457907D02*
X477400D01*
Y458673D01*
X477555Y458980D01*
X477762Y459210D01*
X478072Y459402D01*
X478433Y459555D01*
X478950Y459593D01*
X479467Y459555D01*
X479828Y459402D01*
X480138Y459210D01*
X480345Y458980D01*
X480500Y458673D01*
Y457907D01*
G01X477400Y461850D02*
X477503Y461543D01*
X477762Y461313D01*
X478072Y461160D01*
X478485Y461045D01*
X478950Y461007D01*
X479415Y461045D01*
X479828Y461160D01*
X480138Y461313D01*
X480397Y461543D01*
X480500Y461850D01*
X480397Y462157D01*
X480138Y462387D01*
X479828Y462540D01*
X479415Y462655D01*
X478950Y462693D01*
X478485Y462655D01*
X478072Y462540D01*
X477762Y462387D01*
X477503Y462157D01*
X477400Y461850D01*
M02*
